G04 ================== begin FILE IDENTIFICATION RECORD ==================*
G04 Layout Name:  12432-1.brd*
G04 Film Name:    L3*
G04 File Format:  Gerber RS274X*
G04 File Origin:  Cadence Allegro 16.2-S037*
G04 Origin Date:  Wed Oct 17 11:00:04 2012*
G04 *
G04 Layer:  VIA CLASS/L3*
G04 Layer:  PIN/L3*
G04 Layer:  ETCH/L3*
G04 Layer:  DRAWING FORMAT/LAYER_PCB_STORY*
G04 Layer:  DRAWING FORMAT/LAYER_L3*
G04 *
G04 Offset:    (0.00 0.00)*
G04 Mirror:    No*
G04 Mode:      Positive*
G04 Rotation:  0*
G04 FullContactRelief:  No*
G04 UndefLineWidth:     6.00*
G04 ================== end FILE IDENTIFICATION RECORD ====================*
%FSLAX35Y35*MOIN*%
%IR0*IPPOS*OFA0.00000B0.00000*MIA0B0*SFA1.00000B1.00000*%
%ADD14O,.103X.06*%
%ADD10C,.01*%
%ADD13C,.022*%
%ADD11C,.028*%
%ADD15C,.173*%
%ADD12C,.156*%
%ADD16C,.02*%
%ADD17C,.03*%
%ADD18C,.025*%
%ADD19C,.004*%
%ADD20C,.006*%
%ADD21C,.0045*%
%ADD29O,.12702X.08402*%
%ADD23C,.05204*%
%ADD22C,.04604*%
%ADD27C,.09706*%
%ADD28C,.11506*%
%ADD25C,.18004*%
%ADD26C,.17006*%
%ADD24C,.19704*%
G75*
%LPD*%
G75*
G36*
G01X400728Y1577838D02*
X397776Y1580791D01*
G02X398059Y1581474I283J283D01*
G01X933869D01*
X978227Y1625832D01*
G02X978908Y1625586I283J-283D01*
G03X981414Y1628092I2292J214D01*
G02X981168Y1628773I37J398D01*
G01X987076Y1634681D01*
Y1637097D01*
X987206Y1637146D01*
G03X985911Y1641552I-806J2157D01*
G02X985426Y1641942I-85J391D01*
G01Y1665542D01*
X985513Y1665602D01*
G03X982520Y1665938I-1302J1898D01*
G01X982574Y1665880D01*
Y1661927D01*
G02X981970Y1661582I-400J0D01*
G03X979749Y1661648I-1170J-1982D01*
G01X979653Y1661599D01*
X979461Y1661706D01*
X979434Y1661748D01*
G03X976223Y1662416I-1935J-1248D01*
G02X975602Y1662748I-221J333D01*
G01Y1663584D01*
X977731Y1665714D01*
G03X976876Y1670009I269J2286D01*
G02X976283Y1670408I-196J349D01*
G03X971705Y1670521I-2283J292D01*
G01X971712Y1670429D01*
X964348Y1663066D01*
Y1645435D01*
X965548Y1644235D01*
Y1642202D01*
G02X965149Y1641802I-400J0D01*
G03X962963Y1638781I1J-2302D01*
G02X962453Y1638278I-380J-125D01*
G03X960039Y1634510I-751J-2176D01*
G02X960033Y1633951I-289J-276D01*
G01X953124Y1627041D01*
G02X952476Y1627161I-283J283D01*
G03X949039Y1623724I-2376J-1061D01*
G02X949159Y1623076I-163J-365D01*
G01X927059Y1600976D01*
X335125D01*
X330175Y1596026D01*
X166510D01*
G02X166358Y1596797I-1J400D01*
G01X710522Y1820103D01*
G03X713428Y1823573I1130J2006D01*
G02X713444Y1823845I154J127D01*
G03X709661Y1826223I-1596J1659D01*
G01X709632Y1826135D01*
X161328Y1600507D01*
G03X157965Y1599049I-1127J-2007D01*
G01X157949Y1598984D01*
X157754Y1598826D01*
X157670Y1598836D01*
G03X155100Y1596445I-270J-2286D01*
G02X154701Y1596026I-400J-19D01*
G01X105118D01*
X105117Y1596028D01*
X99584D01*
X99583Y1596026D01*
X95191D01*
X75450Y1615767D01*
Y1623939D01*
X92902Y1641390D01*
Y1641952D01*
X93499Y1642550D01*
Y1660550D01*
X76726Y1677322D01*
Y1691411D01*
X76732Y1691436D01*
X76738Y1691460D01*
G03X74414Y1694300I-2238J540D01*
G02X73999Y1694700I-15J400D01*
G01Y1775398D01*
G02X74399Y1775798I400J0D01*
G01X74400D01*
G03Y1780402I0J2302D01*
G01X74399D01*
G02X73999Y1780802I0J400D01*
G01Y1796835D01*
G02X74685Y1797115I400J0D01*
G03Y1803909I3465J3397D01*
G02X73999Y1804189I-286J280D01*
G01Y1809331D01*
X74056Y1809389D01*
G03Y1815257I-3008J2934D01*
G01X73999Y1815315D01*
Y1815824D01*
X78292D01*
G03Y1818676I1807J1426D01*
G01X72872D01*
X44499Y1847050D01*
X5499D01*
X3000Y1849549D01*
Y1945000D01*
X3548Y1945548D01*
X3689Y1945409D01*
G03X3885Y1948863I1614J1641D01*
G01X3746Y1948754D01*
X3000Y1949500D01*
Y1988000D01*
X4000Y1989000D01*
X1029000D01*
X1029500Y1988500D01*
Y1988499D01*
X1029999Y1988000D01*
Y1744501D01*
X1030000Y1744500D01*
Y1690300D01*
X1027100Y1687400D01*
X1025467D01*
G02X1025189Y1688088I0J400D01*
G03X1017366Y1685930I-5898J6124D01*
G02X1017558Y1685258I-91J-389D01*
G01X1015600Y1683300D01*
Y1625800D01*
X1013900Y1624100D01*
X989772D01*
G02X989377Y1624559I0J400D01*
G03X986325Y1622732I-2277J341D01*
G02X986473Y1622073I-135J-376D01*
G01X984400Y1620000D01*
Y1610600D01*
X989000Y1606000D01*
X1014500D01*
X1016200Y1604300D01*
Y1429300D01*
X1020000Y1425500D01*
X1027500D01*
X1030000Y1423000D01*
Y1270551D01*
X1029999Y1270550D01*
Y4000D01*
X1028999Y3000D01*
X4000D01*
X3000Y4000D01*
Y365051D01*
X4999Y367050D01*
X22999D01*
X27683Y371734D01*
X27782Y371720D01*
G03X30395Y374179I318J2280D01*
G01X30388Y374271D01*
X40126Y384009D01*
Y429309D01*
X61129Y450312D01*
X61221Y450305D01*
G03X63681Y452907I179J2295D01*
G02X64214Y453336I396J53D01*
G03X63251Y456996I786J2164D01*
G01X63191Y456926D01*
X57309D01*
X35624Y435241D01*
Y426541D01*
X29171Y420088D01*
X29079Y420095D01*
G03X27563Y419674I-179J-2295D01*
G01X27425Y419575D01*
X26616Y420384D01*
G02X26825Y421060I283J283D01*
G03X28144Y424823I-426J2262D01*
G02X28154Y425095I152J131D01*
G03X24779Y425219I-1630J1625D01*
G02X24769Y424947I-152J-131D01*
G03X24137Y423748I1630J-1625D01*
G02X23461Y423539I-393J74D01*
G01X21500Y425500D01*
Y661017D01*
G02X22183Y661300I400J0D01*
G01X25009Y658474D01*
X25385D01*
Y658194D01*
X25330Y658136D01*
G03X25682Y654662I1669J-1586D01*
G02X25643Y653982I-229J-328D01*
G03X28054Y653845I1094J-2025D01*
G02X28093Y654525I229J328D01*
G03X28900Y657848I-1094J2025D01*
G02X29230Y658474I330J226D01*
G01X31109D01*
X39074Y650509D01*
Y643207D01*
X39212Y643069D01*
X39205Y642977D01*
G03X42076Y645029I2295J-177D01*
G01X41926Y645068D01*
Y651691D01*
X32291Y661326D01*
X26191D01*
X23026Y664491D01*
Y689809D01*
X24091Y690874D01*
X28664D01*
G02X28947Y690191I0J-400D01*
G01X24174Y685417D01*
Y665909D01*
X27547Y662536D01*
X39671D01*
X41976Y660231D01*
G02X41934Y659628I-283J-283D01*
G03X44798Y655295I1566J-2078D01*
G02X45398Y654949I200J-346D01*
G01Y640915D01*
X41771Y637288D01*
X41679Y637295D01*
G03X39437Y636022I-179J-2295D01*
G02X39181Y635926I-179J89D01*
G03X40363Y632778I-881J-2127D01*
G02X40619Y632874I179J-89D01*
G03X43795Y635179I881J2126D01*
G01X43788Y635271D01*
X48250Y639733D01*
Y640221D01*
G02X48702Y640617I400J-1D01*
G03Y645183I297J2283D01*
G02X48250Y645579I-52J397D01*
G01Y655324D01*
G02X48933Y655607I400J0D01*
G01X53032Y651509D01*
Y640303D01*
X47372Y634643D01*
X47280Y634650D01*
G03X49396Y632534I-179J-2295D01*
G01X49389Y632626D01*
X50223Y633460D01*
G02X50801Y633447I283J-283D01*
G03X54053Y636699I1699J1553D01*
G02X54040Y637277I270J295D01*
G01X55884Y639121D01*
Y652691D01*
X39270Y669306D01*
X35731D01*
X32701Y672335D01*
Y681275D01*
X38200Y686774D01*
Y705043D01*
X35800Y707443D01*
Y711343D01*
G02X36373Y711704I400J0D01*
G03X38299Y716526I1125J2346D01*
G02X38232Y717259I123J381D01*
G03X38949Y717827I-1232J2292D01*
G02X39549I300J-264D01*
G03X43666Y718110I1950J1723D01*
G02X44332I333J-222D01*
G03X48638Y718068I2167J1440D01*
G02X49237Y718135I329J-228D01*
G03X52914Y721812I1762J1915D01*
G02X52981Y722411I295J270D01*
G03X49332Y725990I-1482J2139D01*
G02X48666I-333J222D01*
G03X44549Y726273I-2167J-1440D01*
G02X43949I-300J264D01*
G03X39974Y726184I-1950J-1723D01*
G02X39308Y726250I-311J251D01*
G03X36307Y727558I-2309J-1200D01*
G02X35800Y727944I-107J386D01*
G01Y729563D01*
G02X36240Y729961I400J0D01*
G03Y735139I259J2589D01*
G02X35800Y735537I-40J398D01*
G01Y737063D01*
G02X36240Y737461I400J0D01*
G03X38790Y738817I259J2589D01*
G02X39523Y738750I352J-190D01*
G03X40276Y737600I2476J800D01*
G02Y737000I-264J-300D01*
G03X40059Y733316I1723J-1950D01*
G02Y732784I-299J-266D01*
G03X43761Y729135I1939J-1735D01*
G02X44360Y729068I270J-295D01*
G03X48222Y732500I2139J1482D01*
G02Y733100I264J300D01*
G03X48439Y736784I-1723J1950D01*
G02Y737316I299J266D01*
G03X44737Y740965I-1939J1735D01*
G02X44138Y741032I-270J295D01*
G03X39708Y740783I-2139J-1482D01*
G02X38975Y740850I-352J190D01*
G03X37261Y742538I-2476J-800D01*
G02X37095Y743203I117J382D01*
G01X61182Y767291D01*
Y801234D01*
X62949Y803000D01*
Y816065D01*
G02X63667Y816307I400J0D01*
G03X66996Y819449I1833J1392D01*
G01X66926Y819509D01*
Y822362D01*
X66086Y823202D01*
G02X66402Y823884I283J283D01*
G03X66748Y823870I343J4187D01*
G01X71048D01*
G03Y832272I0J4201D01*
G01X69930D01*
G02X69530Y832666I0J400D01*
G03X69413Y832942I-400J-7D01*
G01X68554Y833801D01*
X72750Y837997D01*
Y845966D01*
X72383Y846334D01*
X72808Y846759D01*
G02X73448Y846657I283J-283D01*
G03X77452Y846480I2052J1043D01*
G01X77511Y846574D01*
X78909D01*
X85748Y839734D01*
Y814735D01*
G02X85066Y814452I-400J0D01*
G01X82788Y816729D01*
X82795Y816821D01*
G03X80679Y814705I-2295J179D01*
G01X80771Y814712D01*
X83074Y812409D01*
Y666154D01*
G02X82352Y665916I-400J0D01*
G03X78889Y666195I-1853J-1366D01*
G02X78609I-140J143D01*
G03Y662905I-1610J-1645D01*
G02X78889I140J-143D01*
G03X82352Y663184I1610J1645D01*
G02X83074Y662946I322J-238D01*
G01X83070Y658057D01*
X43239Y618226D01*
X31509D01*
X27071Y613788D01*
X26979Y613795D01*
G03X29095Y611679I-179J-2295D01*
G01X29088Y611771D01*
X32691Y615374D01*
X42290D01*
G02X42573Y614691I0J-400D01*
G01X41671Y613788D01*
X41579Y613795D01*
G03X39860Y613211I-179J-2295D01*
G02X39588Y613215I-134J149D01*
G03X39539Y609839I-1589J-1665D01*
G02X39811Y609835I134J-149D01*
G03X40089Y609607I1594J1661D01*
G01X40129Y609580D01*
X40231Y609389D01*
X40179Y609294D01*
G03X43583Y606354I2023J-1098D01*
G02X43863Y606314I120J-160D01*
G03X47851Y608522I1838J1386D01*
G02X48136Y609055I374J143D01*
G03X48725Y613323I-510J2245D01*
G02X48633Y613957I191J351D01*
G01X94766Y660090D01*
G02X95449Y659807I283J-283D01*
G01X95448Y649434D01*
X48948Y602933D01*
Y589167D01*
X50254Y587861D01*
Y561851D01*
G02X49845Y561452I-400J1D01*
G03Y556848I-46J-2302D01*
G02X50254Y556449I9J-400D01*
G01Y555273D01*
X48950Y553969D01*
G02X48316Y554059I-283J283D01*
G03X45865Y555211I-2017J-1109D01*
G02X45391Y555640I-76J393D01*
G03X41028Y556855I-2292J210D01*
G02X40453Y556692I-360J174D01*
G03X41288Y553745I-1236J-1942D01*
G02X41863Y553908I360J-174D01*
G03X43533Y553589I1236J1942D01*
G02X44007Y553160I76J-393D01*
G03X45190Y550933I2292J-210D01*
G02X45280Y550299I-193J-351D01*
G01X45059Y550079D01*
G02X44494I-283J283D01*
G03X41238Y546823I-1627J-1629D01*
G02Y546258I-283J-282D01*
G01X36007Y541026D01*
X29008D01*
X28948Y541096D01*
G03Y538104I-1749J-1496D01*
G01X29008Y538174D01*
X37189D01*
X53106Y554091D01*
Y555829D01*
G02X53789Y556112I400J0D01*
G01X66653Y543248D01*
X71004D01*
X71059Y543204D01*
G03X70932Y546685I1441J1795D01*
G02X70266Y546907I-272J293D01*
G03X67821Y548795I-2266J-407D01*
G01X67729Y548788D01*
X56426Y560091D01*
Y590391D01*
X55100Y591717D01*
Y600383D01*
X80224Y625507D01*
G02X80802Y625494I283J-283D01*
G03X84055Y628747I1697J1556D01*
G02X84042Y629325I270J295D01*
G01X101593Y646875D01*
G02X102276Y646592I283J-283D01*
G01X102240Y600843D01*
X102812Y600271D01*
X102805Y600179D01*
G03X105128Y602302I2295J-179D01*
G01Y602534D01*
G02X105746Y602869I400J0D01*
G03X107576Y607029I1253J1931D01*
G01X107426Y607068D01*
Y912091D01*
X96926Y922591D01*
Y957409D01*
X103426Y963909D01*
Y966616D01*
X103504Y966676D01*
G03X104386Y968767I-1404J1824D01*
G01X104375Y968863D01*
X115076Y979564D01*
Y1050059D01*
X126426Y1061409D01*
Y1065909D01*
X128091Y1067574D01*
X143091D01*
X147378Y1071860D01*
Y1109483D01*
X98626Y1158234D01*
Y1308909D01*
X112043Y1322326D01*
G02X112726Y1322043I283J-283D01*
G01Y1321666D01*
X113229Y1321163D01*
X113321Y1321170D01*
G02X113605Y1321175I182J-2295D01*
G03X114024Y1321574I19J400D01*
G01Y1324307D01*
X115605Y1325888D01*
X115724Y1325845D01*
G03X118238Y1326505I775J2168D01*
G02X118832Y1326517I302J-262D01*
G03X118768Y1329604I1675J1579D01*
G02X118174Y1329592I-302J262D01*
G03X116096Y1330280I-1676J-1579D01*
G02X115626Y1330673I-70J394D01*
G01Y1336909D01*
X116814Y1338096D01*
G02X117452Y1337997I283J-283D01*
G03X120996Y1340798I2047J1052D01*
G01X120926Y1340858D01*
Y1358089D01*
G02X121606Y1358374I400J0D01*
G03X123500Y1357598I1895J1926D01*
G01X126390D01*
G02X126776Y1357095I0J-400D01*
G03X127894Y1354480I2224J-596D01*
G01X127920Y1354466D01*
X129698Y1352689D01*
Y1339789D01*
X137966Y1331520D01*
X137980Y1331494D01*
G03X141531Y1330881I2019J1106D01*
G02X142079Y1330866I266J-299D01*
G03X145691Y1331344I1621J1634D01*
G02X146293Y1331451I346J-200D01*
G03X148023Y1330824I1730J2074D01*
G02X148422Y1330424I-1J-400D01*
G01Y1325736D01*
X146320Y1323634D01*
X146294Y1323620D01*
G03X149420Y1320494I1106J-2020D01*
G01X149434Y1320520D01*
X152826Y1323912D01*
Y1329980D01*
X153926Y1331081D01*
Y1335969D01*
X152826Y1337070D01*
Y1363288D01*
X146712Y1369402D01*
X125388D01*
X124020Y1368034D01*
X123994Y1368020D01*
G03X122812Y1366257I1106J-2019D01*
G02X122205Y1365961I-397J45D01*
G03X118911Y1364967I-1205J-1961D01*
G02X118265Y1364852I-363J168D01*
G01X118072Y1365045D01*
Y1366245D01*
X117898Y1366267D01*
G02X116826Y1366700I299J2283D01*
G01Y1400191D01*
X94126Y1422891D01*
Y1548642D01*
X94416D01*
X94475Y1548575D01*
G03X94704Y1548351I1720J1530D01*
G01X94774Y1548291D01*
Y1531709D01*
X97409Y1529074D01*
X152591D01*
X161091Y1537574D01*
X318459D01*
X343061Y1512972D01*
X389190D01*
X389250Y1512902D01*
G03X392688Y1515962I1749J1497D01*
G01X392635Y1516098D01*
X392688Y1516234D01*
X392712Y1516261D01*
G03X392923Y1516533I-1708J1543D01*
G01X392982Y1516624D01*
X736925D01*
X748225Y1527924D01*
X749374D01*
G02X749591Y1527187I1J-400D01*
G03X749060Y1523266I1409J-2187D01*
G02Y1522734I-299J-266D01*
G03Y1519266I1940J-1734D01*
G02Y1518734I-299J-266D01*
G03X752940I1940J-1734D01*
G02Y1519266I299J266D01*
G03Y1522734I-1940J1734D01*
G02Y1523266I299J266D01*
G03X752409Y1527187I-1940J1734D01*
G02X752626Y1527924I216J337D01*
G01X772069D01*
X773194Y1526798D01*
X780466D01*
X781797Y1528130D01*
G02X782438Y1528025I283J-283D01*
G03X785524Y1531111I2061J1025D01*
G02X785419Y1531752I178J358D01*
G01X792767Y1539100D01*
X792898Y1539028D01*
G03X794001Y1543352I1101J2022D01*
G02X793801Y1543552I0J200D01*
G03X790419Y1541517I-2302J-2D01*
G02X790514Y1540881I-188J-353D01*
G01X779284Y1529652D01*
X777244D01*
G02X776844Y1530051I0J400D01*
G03X776216Y1531630I-2302J-1D01*
G02X776221Y1532185I291J275D01*
G03X772428Y1532970I-1644J1611D01*
G02X772055Y1532426I-373J-144D01*
G01X746359D01*
X739909Y1525976D01*
X348505D01*
X348459Y1526003D01*
G03X349402Y1523010I-1135J-2003D01*
G01X349456Y1523124D01*
X738424D01*
G02X738707Y1522441I0J-400D01*
G01X735743Y1519476D01*
X392577D01*
X392520Y1519526D01*
G03X389286Y1516260I-1521J-1728D01*
G01X389310Y1516233D01*
X389363Y1516098D01*
X389311Y1515964D01*
X389287Y1515937D01*
G03X389252Y1515896I1735J-1516D01*
G01X389192Y1515824D01*
X344243D01*
X319641Y1540426D01*
X159909D01*
X151409Y1531926D01*
X99980D01*
G02X99708Y1532620I0J400D01*
G03X100412Y1533914I-1564J1689D01*
G01X100424Y1533984D01*
X100614Y1534148D01*
X100693Y1534144D01*
G03X102557Y1534954I106J2306D01*
G01X102617Y1535024D01*
X153541D01*
X173141Y1554624D01*
X278192D01*
G03X281609Y1554405I1807J1426D01*
G02X281889I140J-143D01*
G03X285572Y1555048I1610J1645D01*
G01X363308D01*
X363884Y1554473D01*
X363870Y1554374D01*
G03X366124Y1556352I2279J-324D01*
G01X366040Y1556351D01*
X364490Y1557902D01*
X356922D01*
G02X356563Y1558479I-1J400D01*
G03X352445Y1560536I-2063J1021D01*
G01X352389Y1560426D01*
X332976D01*
G02X332580Y1560882I0J400D01*
G03X328020I-2280J318D01*
G02X327624Y1560426I-396J-56D01*
G01X172409D01*
X153259Y1541276D01*
X101706D01*
G03X99900Y1542152I-1807J-1426D01*
G02X99500Y1542552I0J400D01*
G01Y1543950D01*
G02X99915Y1544350I400J0D01*
G03X102167Y1545874I85J2300D01*
G01X102182Y1545916D01*
X109926Y1553660D01*
Y1561466D01*
X127515Y1579054D01*
X287045D01*
G02X287439Y1578583I0J-400D01*
G03X288275Y1576164I2559J-470D01*
G02Y1575564I-264J-300D01*
G03Y1571664I1723J-1950D01*
G02Y1571064I-264J-300D01*
G03X291732Y1567174I1723J-1950D01*
G02X292264I266J-299D01*
G03X295721Y1571064I1734J1940D01*
G02Y1571664I264J300D01*
G03Y1575564I-1723J1950D01*
G02Y1576164I264J300D01*
G03X296557Y1578583I-1723J1949D01*
G02X296951Y1579054I394J71D01*
G01X395477D01*
X398711Y1575821D01*
X398704Y1575729D01*
G03X400820Y1577845I2295J-179D01*
G01X400728Y1577838D01*
G37*
G36*
G01X7499Y861050D02*
X5499Y863050D01*
Y870494D01*
G02X6155Y870801I400J0D01*
G03Y879631I3688J4415D01*
G02X5499Y879938I-256J307D01*
G01Y1332674D01*
G02X6155Y1332981I400J0D01*
G03Y1341811I3688J4415D01*
G02X5499Y1342118I-256J307D01*
G01Y1350050D01*
X6999Y1351550D01*
X18747D01*
X18789Y1351406D01*
G03X19963Y1349995I2210J645D01*
G01X20072Y1349939D01*
Y1322661D01*
X19963Y1322605D01*
G03X22956Y1321763I1037J-2055D01*
G01X22926Y1321811D01*
Y1350789D01*
X22956Y1350837D01*
G03X22011Y1354118I-1957J1213D01*
G01X21899Y1354172D01*
Y1393950D01*
X26799Y1398850D01*
Y1404650D01*
X21899Y1409550D01*
Y1521779D01*
G02X22580Y1522063I400J0D01*
G03X25830Y1522076I1618J1637D01*
G02X26514Y1521793I284J-282D01*
G01Y1496684D01*
X34864Y1488334D01*
Y1484385D01*
G02X34464Y1483985I-400J0D01*
G03X33044Y1483494I1J-2302D01*
G02X32767Y1483524I-123J158D01*
G03X32420Y1480239I-1768J-1474D01*
G02X32697Y1480209I123J-158D01*
G03X34464Y1479381I1768J1474D01*
G02X34864Y1478981I0J-400D01*
G01Y1474991D01*
X24168Y1464295D01*
Y1448227D01*
X35128Y1437267D01*
Y1434585D01*
G02X34502Y1434254I-400J0D01*
G03X33001Y1434645I-1297J-1902D01*
G02X32785Y1434821I-17J199D01*
G03X30704Y1432257I-2286J-271D01*
G02X30920Y1432081I17J-199D01*
G03X34502Y1430450I2286J271D01*
G02X35128Y1430119I226J-331D01*
G01Y1412923D01*
G02X34391Y1412708I-400J0D01*
G03X30903Y1413171I-1939J-1240D01*
G02X30627Y1413178I-134J148D01*
G03X30547Y1409847I-1628J-1627D01*
G02X30823Y1409840I134J-148D01*
G03X34391Y1410228I1628J1628D01*
G02X35128Y1410013I337J-215D01*
G01Y1054996D01*
X16872Y1036741D01*
Y1025859D01*
X35098Y1007634D01*
Y863066D01*
X35008Y862976D01*
X28471D01*
X28411Y863046D01*
G03X25916Y863728I-1750J-1496D01*
G02X25418Y863950I-130J378D01*
G03X21444Y861687I-2119J-900D01*
G02X21122Y861050I-322J-237D01*
G01X7499D01*
G37*
G36*
G01X25830Y1525324D02*
G03X22580Y1525337I-1632J-1624D01*
G02X21899Y1525621I-281J284D01*
G01Y1696850D01*
X15799Y1702950D01*
X15513D01*
X15480Y1703110D01*
G03X4485Y1704057I-5637J-1147D01*
G02X3830Y1703919I-373J145D01*
G01X3499Y1704250D01*
Y1754350D01*
X5099Y1755950D01*
X18499D01*
X18772Y1755676D01*
Y1722842D01*
X19299Y1722316D01*
Y1719601D01*
X35282Y1703618D01*
Y1674893D01*
G02X34559Y1674657I-400J0D01*
G03X30898Y1671867I-1860J-1357D01*
G02X30868Y1671335I-313J-249D01*
G03X30830Y1671297I1609J-1647D01*
G02X30559Y1671281I-144J138D01*
G03X30764Y1667909I-1459J-1781D01*
G02X31035Y1667925I144J-138D01*
G03X34296Y1671139I1460J1780D01*
G02X34326Y1671671I313J249D01*
G03X34559Y1671943I-1626J1629D01*
G02X35282Y1671707I323J-236D01*
G01Y1647014D01*
G02X34608Y1646724I-400J1D01*
G03X31438Y1646717I-1581J-1673D01*
G02X31166Y1646713I-138J145D01*
G03X31214Y1643336I-1540J-1711D01*
G02X31486Y1643340I138J-145D01*
G03X34608Y1643378I1540J1711D01*
G02X35282Y1643088I274J-291D01*
G01Y1629722D01*
G02X34554Y1629494I-400J0D01*
G03X32174Y1630430I-1891J-1313D01*
G02X31705Y1630707I-85J391D01*
G03X29988Y1627801I-2206J-657D01*
G02X30457Y1627524I85J-391D01*
G03X34554Y1626868I2206J657D01*
G02X35282Y1626640I328J-228D01*
G01Y1609019D01*
X33998Y1607734D01*
Y1602902D01*
G02X33598Y1602502I-400J0D01*
G03X32410Y1598229I1J-2302D01*
G02X32486Y1597604I-207J-342D01*
G01X31548Y1596665D01*
Y1574677D01*
G02X31055Y1574288I-400J0D01*
G03X29035Y1573808I-535J-2239D01*
G02X28763Y1573820I-130J152D01*
G03X28608Y1570446I-1640J-1615D01*
G02X28880Y1570434I130J-152D01*
G03X31055Y1569810I1640J1615D01*
G02X31548Y1569421I93J-389D01*
G01Y1564165D01*
X27788Y1560406D01*
Y1548641D01*
X26380Y1547233D01*
Y1540833D01*
X23074Y1537526D01*
Y1530358D01*
X26514Y1526918D01*
Y1525607D01*
G02X25830Y1525324I-400J-1D01*
G37*
G36*
G01X31188Y418071D02*
X36591Y423473D01*
G02X37273Y423190I282J-283D01*
G01X37274Y415121D01*
G02X36729Y414747I-400J-1D01*
G03Y410453I-829J-2147D01*
G02X37274Y410079I145J-373D01*
G01Y385191D01*
X29682Y377599D01*
G02X28999Y377882I-283J283D01*
G01Y410450D01*
X29799Y411250D01*
Y413650D01*
X28999Y414450D01*
X28634Y414815D01*
G02X28914Y415498I282J283D01*
G03X31195Y417979I-14J2302D01*
G01X31188Y418071D01*
G37*
G36*
G01X21500Y693283D02*
Y753051D01*
X28965Y760516D01*
G02X29647Y760233I282J-283D01*
G01X29648Y748665D01*
X27274Y746291D01*
Y704933D01*
X30398Y701809D01*
Y693991D01*
X30133Y693726D01*
X22909D01*
X22183Y693000D01*
G02X21500Y693283I-283J283D01*
G37*
G36*
G01X35800Y746910D02*
Y775852D01*
X57647Y797698D01*
G02X58329Y797415I282J-283D01*
G01X58330Y768473D01*
X36483Y746627D01*
G02X35800Y746910I-283J283D01*
G37*
G36*
G01X34718Y1012048D02*
X26544Y1020223D01*
G02X26942Y1020888I283J282D01*
G03X34768Y1022188I2589J8622D01*
G02X35401Y1021863I233J-325D01*
G01Y1012331D01*
G02X34718Y1012048I-400J0D01*
G37*
G36*
G01X20909Y1026921D02*
G02X20244Y1026523I-383J-115D01*
G01X19726Y1027041D01*
Y1035559D01*
X36095Y1051928D01*
G02X36778Y1051645I283J-283D01*
G01Y1045193D01*
X36776Y1045191D01*
Y1045098D01*
X36529Y1044996D01*
X36083Y1045442D01*
G03X35401Y1045159I-282J-283D01*
G01Y1037157D01*
G02X34768Y1036832I-400J0D01*
G03X20909Y1026921I-5237J-7322D01*
G37*
G36*
G01X36095Y1440335D02*
X30326Y1446104D01*
G02Y1446669I283J282D01*
G03X30335Y1446679I-1705J1543D01*
G02X30607Y1446691I142J-141D01*
G03X34383Y1448207I1487J1757D01*
G02X35064Y1448448I398J-42D01*
G01X36778Y1446734D01*
Y1440618D01*
G02X36095Y1440335I-400J0D01*
G37*
G36*
G01X37765Y1449782D02*
X28670Y1458876D01*
Y1460153D01*
G02X29264Y1460503I400J0D01*
G03X32080Y1460968I1114J2015D01*
G02X32363Y1460981I148J-135D01*
G03X32213Y1464231I1552J1700D01*
G02X31930Y1464218I-148J135D01*
G03X31494Y1464531I-1551J-1701D01*
G02X31405Y1465164I194J350D01*
G01X37765Y1471523D01*
G02X38447Y1471240I282J-283D01*
G01X38448Y1450065D01*
G02X37765Y1449782I-400J0D01*
G37*
G36*
G01X36398Y1499473D02*
G02X35716Y1499188I-400J-1D01*
G03X32565Y1499267I-1618J-1638D01*
G02X32033I-266J298D01*
G03X29875Y1499766I-1534J-1717D01*
G02X29366Y1500151I-109J385D01*
G01Y1509221D01*
G02X29818Y1509617I400J-1D01*
G03X31753Y1510282I297J2283D01*
G02X32024Y1510294I142J-140D01*
G03X31874Y1513669I1488J1757D01*
G02X31603Y1513657I-142J140D01*
G03X29818Y1514183I-1488J-1757D01*
G02X29366Y1514579I-52J397D01*
G01Y1516324D01*
G02X30097Y1516549I400J0D01*
G03X33695Y1519403I1901J1298D01*
G02Y1519943I295J270D01*
G03X30097Y1522797I-1697J1556D01*
G02X29366Y1523022I-331J225D01*
G01Y1528100D01*
X25926Y1531540D01*
Y1532120D01*
G02X26383Y1532516I400J0D01*
G03X27191Y1532545I323J2279D01*
G02X27425Y1532406I42J-196D01*
G03X31933Y1533049I2206J657D01*
G02X32130Y1533248I200J-1D01*
G03X32375Y1533265I-37J2302D01*
G02X32822Y1532867I47J-397D01*
G01Y1526702D01*
X33890Y1525633D01*
X35710Y1523813D01*
X36398Y1523125D01*
Y1499473D01*
G37*
G36*
G01X95926Y834958D02*
Y836591D01*
X80591Y851926D01*
X78622D01*
X78566Y852031D01*
G03X76821Y853223I-2026J-1093D01*
G02X76477Y853698I48J397D01*
G03X75716Y855899I-2257J452D01*
G01X75646Y855959D01*
Y973012D01*
X87952Y985317D01*
Y990959D01*
G02X88596Y991276I400J0D01*
G03X92288Y993355I1404J1824D01*
G02X92673Y993799I397J44D01*
G03X93613Y998167I-73J2301D01*
G01X93502Y998222D01*
Y1155599D01*
G02X94184Y1155882I400J0D01*
G01X142574Y1107493D01*
Y1075091D01*
X140409Y1072926D01*
X124909D01*
X120574Y1068591D01*
Y1062591D01*
X110274Y1052291D01*
Y981554D01*
X98474Y969754D01*
Y967246D01*
X98332Y967203D01*
G03X96705Y964821I668J-2203D01*
G01X96712Y964729D01*
X91574Y959591D01*
Y919409D01*
X102276Y908707D01*
Y843700D01*
X100725D01*
X100667Y843796D01*
G03X96421Y842926I-1967J-1196D01*
G01X96412Y842860D01*
X96022Y842470D01*
G03X96063Y841868I282J-283D01*
G02X96970Y839853I-1388J-1836D01*
G01X96963Y839761D01*
X100024Y836701D01*
Y835660D01*
G02X99383Y835340I-400J0D01*
G03X96996Y835572I-1384J-1840D01*
G03X96613Y835390I-46J-398D01*
G02X96534Y835275I-1936J1245D01*
G03X96276Y835026I1465J-1776D01*
G01X96217Y834958D01*
X95926D01*
G37*
G36*
G01X71540Y977609D02*
X70314Y978836D01*
Y987079D01*
X72628Y989394D01*
G02X73310Y989140I283J-283D01*
G03X77667Y984660I4840J348D01*
G02X77910Y983979I-40J-398D01*
G01X71540Y977609D01*
G37*
G36*
G01X62798Y1004227D02*
Y1014192D01*
X66897Y1018291D01*
Y1018380D01*
X69750Y1021233D01*
Y1027566D01*
G02X70433Y1027849I400J0D01*
G01X75898Y1022384D01*
Y1014963D01*
G02X75499Y1014563I-400J0D01*
G03X74531Y1014349I1J-2302D01*
G02X74013Y1014518I-168J363D01*
G03X72969Y1011312I-2013J-1118D01*
G02X73487Y1011143I168J-363D01*
G03X75683Y1009966I2013J1118D01*
G01X75691Y1009967D01*
X75898D01*
Y1009584D01*
X73972Y1007658D01*
Y1005146D01*
G02X73353Y1004812I-400J0D01*
G03X71048Y1005500I-2304J-3513D01*
G01X66748D01*
G03X63507Y1003973I-1J-4201D01*
G02X62798Y1004227I-309J254D01*
G37*
G36*
G01X62799Y989633D02*
X62798Y998371D01*
G02X63507Y998625I400J0D01*
G03X66748Y997098I3240J2674D01*
G01X70263D01*
G02X70546Y996415I0J-400D01*
G01X63481Y989350D01*
G02X62799Y989633I-282J283D01*
G37*
G36*
G01X80766Y1026303D02*
X78600Y1028468D01*
Y1187661D01*
X80766Y1189826D01*
G02X81449Y1189543I283J-283D01*
G01X81448Y1026586D01*
G02X80766Y1026303I-400J0D01*
G37*
G36*
G01X75065Y1029587D02*
X73700Y1030951D01*
Y1185095D01*
X75065Y1186459D01*
G02X75748Y1186176I283J-283D01*
G01Y1029870D01*
G02X75065Y1029587I-400J0D01*
G37*
G36*
G01X68515Y1033827D02*
X62798Y1039543D01*
Y1230655D01*
G02X63507Y1230909I400J0D01*
G03X66748Y1229382I3240J2674D01*
G01X71048D01*
G03X74814Y1231720I0J4202D01*
G02X75572Y1231543I358J-177D01*
G01Y1198359D01*
X75503Y1198299D01*
G03X75977Y1194487I1496J-1749D01*
G02X76083Y1193846I-177J-359D01*
G01X69198Y1186961D01*
Y1034110D01*
G02X68515Y1033827I-400J0D01*
G37*
G36*
G01X86066Y1253101D02*
X76466Y1262700D01*
Y1355191D01*
G02X76998Y1355569I400J0D01*
G03X78487Y1355558I761J2173D01*
G02X79014Y1355179I127J-379D01*
G01Y1353491D01*
X77074Y1351551D01*
Y1332484D01*
X86748Y1322809D01*
X86749Y1253384D01*
G02X86066Y1253101I-400J0D01*
G37*
G36*
G01X66331Y1246787D02*
X64448Y1248669D01*
Y1402620D01*
G02X65014Y1402984I400J0D01*
G03X66748Y1402610I1733J3827D01*
G01X70040D01*
G02X70323Y1401927I0J-400D01*
G01X67014Y1398617D01*
Y1247070D01*
G02X66331Y1246787I-400J0D01*
G37*
G36*
G01X64448Y1411002D02*
Y1419116D01*
G02X65131Y1419399I400J0D01*
G01X73346Y1411184D01*
Y1411003D01*
G02X72781Y1410638I-400J-1D01*
G03X71048Y1411012I-1733J-3828D01*
G01X66748D01*
G03X65014Y1410638I-1J-4201D01*
G02X64448Y1411002I-166J364D01*
G37*
G36*
G01X80556Y1420647D02*
G02X79873Y1420364I-400J0D01*
G01X74348Y1425888D01*
Y1428705D01*
G02X74934Y1429060I400J0D01*
G03Y1433140I1066J2040D01*
G02X74348Y1433495I-186J355D01*
G01Y1559110D01*
G02X74786Y1559508I400J0D01*
G03X76581Y1560127I214J2292D01*
G02X77114Y1560142I275J-291D01*
G03X78716Y1564199I1486J1758D01*
G02X78526Y1564399I10J200D01*
G01Y1569501D01*
G02X79145Y1569836I400J0D01*
G03X79908Y1569517I1255J1930D01*
G02X80194Y1568977I-85J-391D01*
G03X83204Y1565988I2135J-860D01*
G02X83756Y1565618I152J-370D01*
G01Y1563783D01*
G03X83853Y1563522I400J0D01*
G02X83854Y1563000I-303J-262D01*
G03X87023Y1559691I1747J-1499D01*
G02X87582Y1559627I247J-315D01*
G03X91668Y1561252I1791J1446D01*
G01X91661Y1561344D01*
X94080Y1563763D01*
G02X94754Y1563562I283J-283D01*
G03X97838Y1566646I2546J538D01*
G02X97637Y1567320I82J391D01*
G01X112691Y1582374D01*
X123499D01*
G02X123782Y1581691I0J-400D01*
G01X105424Y1563332D01*
Y1556891D01*
X99083Y1550551D01*
G02X98416Y1550725I-282J283D01*
G03X97889Y1551664I-2215J-626D01*
G02X98081Y1552323I293J272D01*
G03X98882Y1556391I-582J2227D01*
G02X98842Y1556670I120J160D01*
G03X94704Y1557871I-1843J1380D01*
G01X94711Y1557779D01*
X85980Y1549048D01*
G02X85297Y1549331I-283J283D01*
G01Y1552943D01*
Y1553343D01*
Y1553823D01*
Y1553861D01*
Y1554150D01*
G03X84984Y1554541I-400J1D01*
G02X84679Y1555016I86J391D01*
G03X80852Y1557177I-2250J484D01*
G02X80577I-138J145D01*
G03Y1553823I-1577J-1677D01*
G02X80852I138J-145D01*
G03X83172Y1553321I1577J1677D01*
G02X83701Y1552943I129J-379D01*
G01Y1547002D01*
X83535Y1546973D01*
G03X82270Y1546297I398J-2267D01*
G02X81694Y1546295I-289J277D01*
G03X80222Y1542396I-1651J-1604D01*
G01X80314Y1542403D01*
X80556Y1542161D01*
Y1420647D01*
G37*
G36*
G01X97359Y1311677D02*
G02X96676Y1311960I-283J283D01*
G01Y1335259D01*
X99426Y1338009D01*
Y1362101D01*
X102391Y1365065D01*
G02X103073Y1364782I282J-283D01*
G01X103074Y1350837D01*
G02X102626Y1350439I-400J-1D01*
G03X100654Y1346597I-276J-2285D01*
G02Y1346057I-295J-270D01*
G03X102626Y1342215I1696J-1557D01*
G02X103074Y1341817I48J-397D01*
G01Y1324065D01*
G02X102677Y1323665I-400J0D01*
G03X104995Y1321542I23J-2302D01*
G01X104988Y1321634D01*
X105926Y1322572D01*
Y1364409D01*
X109476Y1367959D01*
Y1402540D01*
G02X110159Y1402823I400J0D01*
G01X113974Y1399009D01*
Y1365109D01*
X115874Y1363209D01*
Y1350000D01*
G02X115181Y1349726I-400J-1D01*
G03X111804Y1346597I-1681J-1572D01*
G02Y1346057I-295J-270D01*
G03X115181Y1342928I1696J-1557D01*
G02X115874Y1342654I293J-273D01*
G01Y1341191D01*
X112774Y1338091D01*
Y1337686D01*
X112750Y1337642D01*
G03X112726Y1337547I176J-95D01*
G01Y1327043D01*
X97359Y1311677D01*
G37*
G36*
G01X89891Y1351874D02*
X94026Y1356009D01*
Y1406725D01*
G02X94709Y1407008I400J0D01*
G01X101674Y1400044D01*
Y1371141D01*
X94624Y1364091D01*
Y1340541D01*
X90648Y1336566D01*
Y1327160D01*
G02X89966Y1326877I-400J0D01*
G01X83816Y1333026D01*
Y1348399D01*
X87291Y1351874D01*
X89891D01*
G37*
G36*
G01X141081Y1334633D02*
X134100Y1341613D01*
Y1354513D01*
X131033Y1357581D01*
X131019Y1357606D01*
G03X129788Y1358663I-2019J-1106D01*
G02X129642Y1359322I137J376D01*
G01X131119Y1360798D01*
X137381D01*
X138798Y1359381D01*
Y1338930D01*
X142615Y1335113D01*
G02X142535Y1334485I-283J-283D01*
G03X142169Y1334219I1164J-1986D01*
G02X141621Y1334234I-266J299D01*
G03X141106Y1334619I-1622J-1633D01*
G01X141081Y1334633D01*
G37*
G36*
G01X144202Y1361619D02*
X141505Y1364316D01*
G02X141788Y1364998I283J282D01*
G01X144888D01*
X148422Y1361464D01*
Y1337913D01*
G02X147740Y1337630I-400J0D01*
G01X144202Y1341168D01*
Y1361619D01*
G37*
G36*
G01X338791Y1581908D02*
G02X338508Y1582590I0J400D01*
G01X341491Y1585574D01*
X348314D01*
G02X348530Y1584837I0J-400D01*
G03X347528Y1582395I1244J-1937D01*
G02X347138Y1581908I-390J-87D01*
G01X338791D01*
G37*
%LPC*%
G75*
G36*
G01X884696Y1739970D02*
G03X885255Y1739916I307J256D01*
G02X884904Y1736230I1645J-2016D01*
G03X884345Y1736284I-307J-256D01*
G02X884696Y1739970I-1645J2016D01*
G37*
G36*
G01X307042Y1966434D02*
G02X304956I-1043J-2384D01*
G03Y1967166I-161J366D01*
G02X307042I1043J2384D01*
G03Y1966434I161J-366D01*
G37*
G36*
G01X771383Y1929007D02*
G02Y1931093I-2384J1043D01*
G03X772115I366J161D01*
G02Y1929007I2384J-1043D01*
G03X771383I-366J-161D01*
G37*
G36*
G01X754634Y1764060D02*
G02X751271Y1768029I-1734J1940D01*
G03X751359Y1768555I-250J312D01*
G02X754997Y1772114I2199J1391D01*
G03X755525Y1772190I222J333D01*
G02X755657Y1772335I1989J-1678D01*
G03X755454Y1773006I-286J280D01*
G02X754265Y1773610I545J2544D01*
G03X753733I-266J-299D01*
G02X750370Y1777579I-1734J1940D01*
G03X750458Y1778105I-250J312D01*
G02X754096Y1781664I2199J1391D01*
G03X754624Y1781740I222J333D01*
G02X758027Y1777880I1993J-1673D01*
G03X757944Y1777278I216J-337D01*
G02X757860Y1773732I-1945J-1728D01*
G03X758063Y1773061I286J-280D01*
G02X758928Y1768330I-545J-2544D01*
G03X758845Y1767728I216J-337D01*
G02X755166Y1764060I-1946J-1728D01*
G03X754634I-266J-299D01*
G37*
G36*
G01X154928Y1678143D02*
G02X150884Y1676471I-2295J-176D01*
G01X150824Y1676540D01*
X148575D01*
X123126Y1701990D01*
X123024Y1701973D01*
G02X121014Y1705871I-382J2270D01*
G03Y1706436I-283J283D01*
G01X117648Y1709803D01*
Y1713510D01*
X115458Y1715699D01*
G03X114817Y1715594I-283J-283D01*
G02X111128Y1718243I-2064J1019D01*
G03X111099Y1718835I-283J283D01*
G02X114857Y1720434I1463J1778D01*
G01X114850Y1720342D01*
X120500Y1714692D01*
Y1710985D01*
X120836Y1710650D01*
G03X121508Y1711024I283J283D01*
G02X123223Y1709309I2241J526D01*
G03X122849Y1708637I-91J-389D01*
G01X126557Y1704929D01*
G03X127122I283J283D01*
G02X130378Y1701673I1627J-1629D01*
G03Y1701108I283J-283D01*
G01X130464Y1701021D01*
G03X131094Y1701105I283J283D01*
G02X135109Y1701065I1996J-1146D01*
G01X135123Y1701040D01*
X148161Y1688002D01*
X168427D01*
X168454Y1688010D01*
G02X168543Y1688034I644J-2211D01*
G03X168729Y1688705I-97J388D01*
G01X153298Y1704135D01*
Y1711628D01*
G03X152617Y1711913I-400J1D01*
G02Y1715187I-1618J1637D01*
G03X153298Y1715472I281J284D01*
G01Y1769865D01*
X98792Y1824371D01*
G03X98227I-282J-283D01*
G02X94390Y1825357I-1627J1629D01*
G03X93931Y1825639I-384J-111D01*
G02X91890Y1826255I-431J2261D01*
G03X91610I-140J-143D01*
G02X87790Y1828546I-1610J1645D01*
G01X87798Y1828573D01*
Y1829838D01*
X91962Y1834002D01*
X99915D01*
X160902Y1773015D01*
Y1728658D01*
G03X161594Y1728386I400J1D01*
G02X162813Y1729123I1904J-1773D01*
G03X163079Y1729656I-106J386D01*
G02X167542Y1732225I2420J958D01*
G03X168208Y1732283I314J248D01*
G02X172755Y1729753I2291J-1233D01*
G03X173021Y1729162I347J-199D01*
G02X170549Y1724890I-522J-2549D01*
G03X169949I-300J-264D01*
G02X166049I-1950J1723D01*
G03X165449I-300J-264D01*
G02X161594Y1724840I-1950J1723D01*
G03X160902Y1724568I-292J-273D01*
G01Y1716866D01*
G03X161461Y1716499I400J0D01*
G02X164666Y1715553I1038J-2386D01*
G03X165332I333J222D01*
G02X169684Y1715526I2167J-1440D01*
G03X170350Y1715517I336J217D01*
G02X175024Y1714679I2149J-1467D01*
G01X175037Y1714625D01*
X183302Y1706361D01*
Y1683373D01*
X183310Y1683346D01*
G02X183278Y1681956I-2210J-644D01*
G03X183657Y1681426I379J-130D01*
G01X305209D01*
X329009Y1705226D01*
X376091D01*
X376151Y1705296D01*
G02Y1702304I1749J-1496D01*
G01X376091Y1702374D01*
X330191D01*
X306391Y1678574D01*
X171321D01*
X171195Y1678448D01*
X168005D01*
X167879Y1678574D01*
X155327D01*
G03X154928Y1678143I0J-400D01*
G37*
G36*
G01X129306Y1567294D02*
G02X127247Y1566527I-206J-2594D01*
G03X126994Y1567206I-285J280D01*
G02X129053Y1567973I206J2594D01*
G03X129306Y1567294I285J-280D01*
G37*
G36*
G01X564542Y1488934D02*
G02X562456I-1043J-2384D01*
G03Y1489666I-161J366D01*
G02Y1494434I1043J2384D01*
G03Y1495166I-161J366D01*
G02X564542I1043J2384D01*
G03Y1494434I161J-366D01*
G02Y1489666I-1043J-2384D01*
G03Y1488934I161J-366D01*
G37*
G36*
G01X967723Y1476950D02*
G02X964277I-1723J-1950D01*
G03Y1477550I-264J300D01*
G02Y1481450I1723J1950D01*
G03Y1482050I-264J300D01*
G02X964656Y1486228I1723J1950D01*
G03X964616Y1486934I-206J342D01*
G02X967044Y1487072I1083J2366D01*
G03X967084Y1486366I206J-342D01*
G02X967723Y1482050I-1084J-2366D01*
G03Y1481450I264J-300D01*
G02Y1477550I-1723J-1950D01*
G03Y1476950I264J-300D01*
G37*
G36*
G01X975223Y1475950D02*
G02X971777I-1723J-1950D01*
G03Y1476550I-264J300D01*
G02Y1480450I1723J1950D01*
G03Y1481050I-264J300D01*
G02X972156Y1485228I1723J1950D01*
G03X972116Y1485934I-206J342D01*
G02X974544Y1486072I1083J2366D01*
G03X974584Y1485366I206J-342D01*
G02X975223Y1481050I-1084J-2366D01*
G03Y1480450I264J-300D01*
G02Y1476550I-1723J-1950D01*
G03Y1475950I264J-300D01*
G37*
G36*
G01X960523Y1474450D02*
G02X957077I-1723J-1950D01*
G03Y1475050I-264J300D01*
G02Y1478950I1723J1950D01*
G03Y1479550I-264J300D01*
G02X957456Y1483728I1723J1950D01*
G03X957416Y1484434I-206J342D01*
G02X959844Y1484572I1083J2366D01*
G03X959884Y1483866I206J-342D01*
G02X960523Y1479550I-1084J-2366D01*
G03Y1478950I264J-300D01*
G02Y1475050I-1723J-1950D01*
G03Y1474450I264J-300D01*
G37*
G36*
G01X179476Y1367225D02*
G03X179402Y1367877I-265J300D01*
G02X179119Y1371741I1098J2023D01*
G01X179198Y1371801D01*
Y1415438D01*
X231498Y1467738D01*
Y1469844D01*
G03X230792Y1470100I-400J-1D01*
G02Y1473052I-1767J1476D01*
G03X231498Y1473308I306J257D01*
G01Y1480927D01*
X231490Y1480954D01*
G02X235910I2210J646D01*
G01X235902Y1480927D01*
Y1468581D01*
G03X236584Y1468298I400J0D01*
G01X238967Y1470681D01*
X238981Y1470706D01*
G02X242106Y1467581I2019J-1106D01*
G01X242081Y1467567D01*
X186802Y1412288D01*
Y1368188D01*
X183033Y1364419D01*
X183019Y1364394D01*
G02X179476Y1367225I-2019J1106D01*
G37*
G36*
G01X750629Y1113044D02*
G02X746802Y1113523I-2130J-1494D01*
G03X746869Y1114056I-261J303D01*
G02X747597Y1117742I2130J1494D01*
G03X747731Y1118275I-215J337D01*
G02X748204Y1121434I2268J1275D01*
G03X747928Y1122124I-276J290D01*
G01X374808D01*
X374748Y1122054D01*
G02Y1125046I-1749J1496D01*
G01X374808Y1124976D01*
X760408D01*
X771408Y1135976D01*
X787378D01*
G03X787692Y1136624I0J400D01*
G02X791775Y1138392I1807J1426D01*
G03X791988Y1138222I198J30D01*
G02X791975Y1133631I166J-2296D01*
G01X791883Y1133638D01*
X791369Y1133124D01*
X781620D01*
G03X781306Y1132476I0J-400D01*
G02X777692I-1807J-1426D01*
G03X777378Y1133124I-314J248D01*
G01X772590D01*
X772488Y1133021D01*
G03X772730Y1132340I283J-283D01*
G02X770209Y1129819I-231J-2290D01*
G03X769528Y1130061I-398J-41D01*
G01X761590Y1122124D01*
X752070D01*
G03X751794Y1121434I0J-400D01*
G02X752475Y1120350I-1795J-1884D01*
G03X753208Y1120283I381J123D01*
G02X753023Y1118250I2291J-1233D01*
G03X752290Y1118317I-381J-123D01*
G02X751401Y1117358I-2291J1233D01*
G03X751267Y1116825I215J-337D01*
G02X750696Y1113577I-2268J-1275D01*
G03X750629Y1113044I261J-303D01*
G37*
G36*
G01X157542Y872934D02*
G02X155456I-1043J-2384D01*
G03Y873666I-161J366D01*
G02X157542I1043J2384D01*
G03Y872934I161J-366D01*
G37*
G36*
G01X28915Y575704D02*
G02X26739Y575842I-1216J-1954D01*
G03X26784Y576546I-166J364D01*
G02X28960Y576408I1216J1954D01*
G03X28915Y575704I166J-364D01*
G37*
G36*
G01X135604Y545630D02*
X135611Y545722D01*
X119774Y561559D01*
Y803591D01*
X151244Y835061D01*
X151257Y835117D01*
G02X152478Y836663I2243J-517D01*
G03X152670Y837173I-178J358D01*
G02X157094Y837871I2129J877D01*
G01X157087Y837779D01*
X157452Y837414D01*
Y761141D01*
X160289Y758304D01*
G03X160972Y758583I283J283D01*
G02X165173Y762744I4201J-40D01*
G01X169473D01*
G02Y754342I0J-4201D01*
G01X165173D01*
G02X164731Y754365I-3J4201D01*
G01X164636Y754375D01*
X164427Y754166D01*
X167126Y751467D01*
Y595160D01*
X155926Y583960D01*
Y576468D01*
G03X156426Y576080I400J0D01*
G02X157646Y576061I575J-2229D01*
G01X157673Y576052D01*
X158178D01*
G03X158570Y576534I0J400D01*
G02X161470Y579210I2254J466D01*
G01X161497Y579202D01*
X176923D01*
X206073Y608352D01*
X206789D01*
X207198Y608760D01*
Y609476D01*
X236298Y638577D01*
Y680127D01*
X236290Y680154D01*
G02X240219Y682331I2210J646D01*
G03X240801Y682314I299J266D01*
G01X247598Y689112D01*
Y689227D01*
X247590Y689254D01*
G02X252010I2210J646D01*
G01X252002Y689227D01*
Y689132D01*
G03X252684Y688849I400J0D01*
G01X265961Y702125D01*
X265974Y702179D01*
G02X267059Y703717I2525J-629D01*
G03Y704383I-222J333D01*
G02Y708717I1440J2167D01*
G03Y709383I-222J333D01*
G02Y713717I1440J2167D01*
G03Y714383I-222J333D01*
G02X269939I1440J2167D01*
G03Y713717I222J-333D01*
G02Y709383I-1440J-2167D01*
G03Y708717I222J-333D01*
G02Y704383I-1440J-2167D01*
G03Y703717I222J-333D01*
G02X269128Y699025I-1440J-2167D01*
G01X269074Y699012D01*
X251907Y681845D01*
X251893Y681799D01*
G02X247475Y681911I-2193J701D01*
G03X246805Y682092I-387J-102D01*
G01X243902Y679188D01*
Y635427D01*
X214800Y606326D01*
Y605610D01*
X209939Y600748D01*
X209223D01*
X183236Y574762D01*
Y574761D01*
X180074Y571598D01*
X158585D01*
X158534Y571650D01*
X157673D01*
X157646Y571641D01*
G02X156426Y571622I-645J2210D01*
G03X155926Y571234I-100J-388D01*
G01Y561591D01*
X162041Y555476D01*
X180806D01*
G03X181205Y555910I0J400D01*
G02X185793I2294J190D01*
G03X186192Y555476I399J-34D01*
G01X198091D01*
X198151Y555546D01*
G02Y552554I1749J-1496D01*
G01X198091Y552624D01*
X160859D01*
X159471Y554011D01*
G03X158790Y553769I-283J-283D01*
G02X156269Y556290I-2290J231D01*
G03X156511Y556971I-41J398D01*
G01X153074Y560409D01*
Y585142D01*
X159697Y591765D01*
G03X159312Y592435I-283J283D01*
G02X162762Y595885I-1241J4691D01*
G03X163432Y595500I387J-102D01*
G01X164274Y596342D01*
Y750285D01*
X154600Y759959D01*
Y808076D01*
G03X153973Y808406I-400J0D01*
G02X151456Y812934I-1474J2144D01*
G03Y813666I-161J366D01*
G02X150776Y818000I1043J2384D01*
G03Y818600I-264J300D01*
G02Y822500I1723J1950D01*
G03Y823100I-264J300D01*
G02X153973Y827194I1723J1950D01*
G03X154600Y827524I227J330D01*
G01Y831990D01*
G03X154096Y832376I-400J0D01*
G02X152784Y832412I-595J2224D01*
G01X152668Y832450D01*
X122626Y802409D01*
Y562741D01*
X137628Y547739D01*
X137720Y547746D01*
G02X135604Y545630I179J-2295D01*
G37*
G36*
G01X189222Y533563D02*
G02X185776I-1723J-1950D01*
G03Y534163I-264J300D01*
G02X186918Y538649I1723J1950D01*
G03X187118Y539315I-89J390D01*
G02X187276Y543063I1881J1798D01*
G03Y543663I-264J300D01*
G02X187059Y547347I1723J1950D01*
G03Y547879I-299J266D01*
G02X190949Y551336I1940J1734D01*
G03X191549I300J264D01*
G02X195605Y548085I1950J-1723D01*
G03X195671Y547543I323J-236D01*
G02X195511Y543432I-1672J-1994D01*
G03X195444Y542841I232J-326D01*
G02X191549Y539390I-1945J-1728D01*
G03X190949I-300J-264D01*
G02X189580Y538577I-1949J1723D01*
G03X189380Y537911I89J-390D01*
G02X189222Y534163I-1881J-1798D01*
G03Y533563I264J-300D01*
G37*
G36*
G01X150515Y522572D02*
G02X150050Y519589I1485J-1759D01*
G03X149429Y519659I-338J-213D01*
G02X146172Y523681I-1839J1840D01*
G03X146133Y524374I-218J335D01*
G02X148718Y524519I1166J2326D01*
G03X148757Y523826I218J-335D01*
G02X149902Y522694I-1167J-2326D01*
G03X150515Y522572I355J184D01*
G37*
G36*
G01X810813Y294738D02*
G02X807933I-1440J-2167D01*
G03Y295404I-222J333D01*
G02X808162Y299874I1440J2167D01*
G03X808112Y300604I-186J354D01*
G02X807462Y305150I887J2446D01*
G03X807512Y305752I-236J323D01*
G02X810910Y305471I1861J1819D01*
G03X810860Y304869I236J-323D01*
G02X810210Y300747I-1861J-1819D01*
G03X810260Y300017I186J-354D01*
G02X810813Y295404I-887J-2446D01*
G03Y294738I222J-333D01*
G37*
G36*
G01X928893Y113742D02*
G02X928513Y116784I-1894J1308D01*
G03X929105Y116858I263J302D01*
G02X931745Y117728I1894J-1308D01*
G03X932263Y118201I130J378D01*
G02X935270Y120919I2236J549D01*
G03X935789Y121407I135J377D01*
G02X937228Y119881I2210J643D01*
G03X936709Y119393I-135J-377D01*
G02X933753Y116572I-2210J-643D01*
G03X933235Y116099I-130J-378D01*
G02X929485Y113816I-2236J-549D01*
G03X928893Y113742I-263J-302D01*
G37*
G36*
G01X207516Y106659D02*
G02X205611Y107849I-2017J-1109D01*
G03X205982Y108441I20J400D01*
G02X207887Y107251I2017J1109D01*
G03X207516Y106659I-20J-400D01*
G37*
G36*
G01X168676Y105290D02*
G02X167422Y103410I1323J-2241D01*
G03X166822Y103810I-396J56D01*
G02X168076Y105690I-1323J2241D01*
G03X168676Y105290I396J-56D01*
G37*
G36*
G01X944542Y74934D02*
G02X942456I-1043J-2384D01*
G03Y75666I-161J366D01*
G02X941983Y80165I1043J2384D01*
G03X942009Y80795I-233J325D01*
G02X944989I1490J1755D01*
G03X945015Y80165I259J-305D01*
G02X944542Y75666I-1516J-2115D01*
G03Y74934I161J-366D01*
G37*
G36*
G01X226542Y54934D02*
G02X224456I-1043J-2384D01*
G03Y55666I-161J366D01*
G02Y60434I1043J2384D01*
G03Y61166I-161J366D01*
G02X224312Y65865I1043J2384D01*
G03X224332Y66566I-183J356D01*
G02X226666I1167J1984D01*
G03X226686Y65865I203J-345D01*
G02X226542Y61166I-1187J-2315D01*
G03Y60434I161J-366D01*
G02Y55666I-1043J-2384D01*
G03Y54934I161J-366D01*
G37*
G36*
G01X294383Y38133D02*
X306501Y50252D01*
X312997D01*
X317200Y46048D01*
Y41052D01*
X284997Y8848D01*
X149001D01*
X140439Y17411D01*
G03X139757Y17151I-283J-283D01*
G02X121596Y22985I-9836J565D01*
G03X121258Y23598I-338J213D01*
G01X95251D01*
X78298Y40552D01*
Y46048D01*
X80001Y47752D01*
X82133D01*
G03X82416Y48434I0J400D01*
G01X81798Y49052D01*
Y55548D01*
X84001Y57752D01*
X101497D01*
X113497Y45752D01*
X147497D01*
X160997Y32252D01*
X272501D01*
X286001Y45752D01*
X289997D01*
X293700Y42048D01*
Y38416D01*
G03X294383Y38133I400J0D01*
G37*
G36*
G01X374549Y13827D02*
G03X373949I-300J-264D01*
G02X369458Y16110I-1950J1723D01*
G03X369192Y16576I-391J86D01*
G02X368276Y21000I807J2474D01*
G03Y21600I-264J300D01*
G02X371722I1723J1950D01*
G03Y21000I264J-300D01*
G02X372540Y18490I-1723J-1950D01*
G03X372806Y18024I391J-86D01*
G02X373949Y17273I-807J-2474D01*
G03X374549I300J264D01*
G02X378449I1950J-1723D01*
G03X379049I300J264D01*
G02X380136Y18005I1950J-1723D01*
G03X380336Y18604I-133J377D01*
G02X383362Y17595I2163J1446D01*
G03X383162Y16996I133J-377D01*
G02X379049Y13827I-2163J-1446D01*
G03X378449I-300J-264D01*
G02X374549I-1950J1723D01*
G37*
G36*
G01X943474Y31916D02*
G03X942808Y31850I-311J-251D01*
G02X942524Y34684I-2309J1200D01*
G03X943190Y34750I311J251D01*
G02X943474Y31916I2309J-1200D01*
G37*
G36*
G01X192327Y37906D02*
G03X191727Y37806I-257J-306D01*
G02X191171Y41144I-2228J1344D01*
G03X191771Y41244I257J306D01*
G02X192361Y41922I2228J-1343D01*
G03X192428Y42475I-251J311D01*
G02X196865Y42968I2071J1575D01*
G03X197332Y42415I364J-166D01*
G02X196265Y37960I667J-2515D01*
G03X195733I-266J-299D01*
G02X192327Y37906I-1734J1940D01*
G37*
G36*
G01X930481Y53911D02*
G03X930414Y53312I228J-329D01*
G02X927017Y53689I-1915J-1762D01*
G03X927084Y54288I-228J329D01*
G02Y57812I1915J1762D01*
G03X927017Y58411I-295J270D01*
G02X927299Y62859I1482J2139D01*
G03X927365Y63525I-185J355D01*
G02X930199Y63241I1634J2025D01*
G03X930133Y62575I185J-355D01*
G02X930414Y58788I-1634J-2025D01*
G03X930481Y58189I295J-270D01*
G02Y53911I-1482J-2139D01*
G37*
G36*
G01X383644Y55440D02*
G03Y55160I143J-140D01*
G02X380354I-1645J-1610D01*
G03Y55440I-143J140D01*
G02X383644I1645J1610D01*
G37*
G36*
G01X906633Y59525D02*
G03X906699Y58859I251J-311D01*
G02X903865Y58575I-1200J-2309D01*
G03X903799Y59241I-251J311D01*
G02X906633Y59525I1200J2309D01*
G37*
G36*
G01X944439Y64383D02*
G03Y63717I222J-333D01*
G02X941559I-1440J-2167D01*
G03Y64383I-222J333D01*
G02X944439I1440J2167D01*
G37*
G36*
G01X357076Y62816D02*
X357166Y62952D01*
X324184Y95933D01*
G03X323502Y95650I-282J-283D01*
G01Y93312D01*
X325135Y91678D01*
X325197Y91667D01*
G02X324154Y87190I-397J-2267D01*
G01X324127Y87198D01*
X323388D01*
X319098Y91488D01*
Y96493D01*
X317038Y98554D01*
X316907Y98481D01*
G02X313781Y99394I-1107J2019D01*
G01X313767Y99419D01*
X260599Y152588D01*
X146449D01*
X100993Y198044D01*
G03X100349Y197933I-283J-283D01*
G02X96882Y201400I-2350J1117D01*
G03X96993Y202044I-172J361D01*
G01X96688Y202348D01*
X96023D01*
X95996Y202340D01*
G02X93380Y205741I-646J2210D01*
G03X93038Y206348I-342J207D01*
G01X90473D01*
X90446Y206340D01*
G02Y210760I-646J2210D01*
G01X90473Y210752D01*
X98187D01*
G03X98470Y211434I0J400D01*
G01X95281Y214624D01*
X67808D01*
X67748Y214554D01*
G02Y217546I-1749J1496D01*
G01X67808Y217476D01*
X96463D01*
X131051Y182889D01*
X146516Y167422D01*
G03X147198Y167705I282J283D01*
G01Y169612D01*
X151588Y174002D01*
X167691D01*
X168608Y174919D01*
G03X168325Y175602I-283J283D01*
G01X165173D01*
G02Y184004I0J4201D01*
G01X169473D01*
G02X171840Y176332I0J-4201D01*
G03X172066Y175602I226J-330D01*
G01X174727D01*
X236648Y237523D01*
Y276488D01*
X237398Y277238D01*
Y277927D01*
X237390Y277954D01*
G02X241810I2210J646D01*
G01X241802Y277927D01*
Y277598D01*
G03X242143Y277456I200J0D01*
G01X248122Y283435D01*
X248133Y283497D01*
G02X252512Y284015I2267J-397D01*
G03X253162Y283891I367J159D01*
G01X264960Y295689D01*
X264973Y295743D01*
G02X266058Y297281I2525J-629D01*
G03Y297947I-222J333D01*
G02Y302281I1440J2167D01*
G03Y302947I-222J333D01*
G02Y307281I1440J2167D01*
G03Y307947I-222J333D01*
G02X268938I1440J2167D01*
G03Y307281I222J-333D01*
G02Y302947I-1440J-2167D01*
G03Y302281I222J-333D01*
G02Y297947I-1440J-2167D01*
G03Y297281I222J-333D01*
G02X268127Y292589I-1440J-2167D01*
G01X268073Y292576D01*
X252502Y277004D01*
Y275773D01*
X252510Y275746D01*
G02X248090I-2210J-646D01*
G01X248098Y275773D01*
Y276219D01*
G03X247416Y276502I-400J0D01*
G01X244252Y273338D01*
Y234373D01*
X177877Y167998D01*
X175878D01*
G03X175526Y167409I0J-400D01*
G02X171198Y166276I-2026J-1093D01*
G01X171197Y166357D01*
X170998Y166556D01*
X170741Y166298D01*
X154873D01*
X154846Y166290D01*
G02X152011Y167787I-646J2210D01*
G01X151996Y167832D01*
X151821Y168008D01*
X151602Y167788D01*
Y167073D01*
X151610Y167046D01*
G02X150379Y164316I-2210J-646D01*
G03X150266Y163672I170J-362D01*
G01X152097Y161840D01*
X224566D01*
X227627Y164902D01*
X230571D01*
X233632Y161840D01*
X264433D01*
X320541Y105732D01*
G03X321205Y105894I283J283D01*
G02X323274Y102901I2195J-694D01*
G03X322852Y102502I-22J-399D01*
G01Y101300D01*
X352037Y72116D01*
G03X352716Y72347I283J283D01*
G02X355296Y69767I2283J-297D01*
G03X355065Y69088I52J-396D01*
G01X360426Y63727D01*
Y63359D01*
X360495Y63299D01*
G02X357076Y62816I-1497J-1749D01*
G37*
G36*
G01X343018Y65381D02*
G03Y64779I264J-301D01*
G02X339980I-1519J-1729D01*
G03Y65381I-264J301D01*
G02X343018I1519J1729D01*
G37*
G36*
G01X379549Y63827D02*
G03X378949I-300J-264D01*
G02X375276Y67500I-1950J1723D01*
G03Y68100I-264J300D01*
G02X378949Y71773I1723J1950D01*
G03X379549I300J264D01*
G02X383222Y68100I1950J-1723D01*
G03Y67500I264J-300D01*
G02X379549Y63827I-1723J-1950D01*
G37*
G36*
G01X291779Y70653D02*
G03X291913Y69986I274J-292D01*
G02X289219Y69447I-914J-2436D01*
G03X289085Y70114I-274J292D01*
G02X287637Y73642I914J2436D01*
G03X287437Y74175I-363J168D01*
G02X287097Y78742I1062J2375D01*
G03X287231Y79275I-215J337D01*
G02X290901Y78358I2268J1275D01*
G03X290767Y77825I215J-337D01*
G02X290861Y75458I-2268J-1275D01*
G03X291061Y74925I363J-168D01*
G02X291779Y70653I-1062J-2375D01*
G37*
G36*
G01X77191Y68961D02*
G03X76643Y68939I-262J-302D01*
G02X73354Y72160I-1644J1611D01*
G03Y72440I-143J140D01*
G02X76508Y75789I1645J1611D01*
G03X77056Y75811I262J302D01*
G02X80345Y72590I1645J-1611D01*
G03Y72310I143J-140D01*
G02X77191Y68961I-1645J-1611D01*
G37*
G36*
G01X306454Y74913D02*
G03X307053Y74713I377J133D01*
G02X306044Y71687I1446J-2163D01*
G03X305445Y71887I-377J-133D01*
G02X306454Y74913I-1446J2163D01*
G37*
G36*
G01X159939Y81883D02*
G03Y81217I222J-333D01*
G02X157059I-1440J-2167D01*
G03Y81883I-222J333D01*
G02X156776Y86000I1440J2167D01*
G03Y86600I-264J300D01*
G02X157059Y90717I1723J1950D01*
G03Y91383I-222J333D01*
G02X159939I1440J2167D01*
G03Y90717I222J-333D01*
G02X160222Y86600I-1440J-2167D01*
G03Y86000I264J-300D01*
G02X159939Y81883I-1723J-1950D01*
G37*
G36*
G01X168222Y81600D02*
G03Y81000I264J-300D01*
G02X164776I-1723J-1950D01*
G03Y81600I-264J300D01*
G02X165017Y85689I1723J1950D01*
G03X165084Y86288I-228J329D01*
G02X165276Y90000I1915J1762D01*
G03Y90600I-264J300D01*
G02Y94500I1723J1950D01*
G03Y95100I-264J300D01*
G02X168722I1723J1950D01*
G03Y94500I264J-300D01*
G02Y90600I-1723J-1950D01*
G03Y90000I264J-300D01*
G02X168481Y85911I-1723J-1950D01*
G03X168414Y85312I228J-329D01*
G02X168222Y81600I-1915J-1762D01*
G37*
G36*
G01X177295Y77502D02*
G03X176703I-296J-269D01*
G02Y80598I-1704J1548D01*
G03X177295I296J269D01*
G02Y77502I1704J-1548D01*
G37*
G36*
G01X76188Y82486D02*
G03Y82214I147J-136D01*
G02X72810I-1689J-1564D01*
G03Y82486I-147J136D01*
G02X76188I1689J1564D01*
G37*
G36*
G01X841600Y85137D02*
G03X842199Y84804I400J14D01*
G02X840898Y82463I1300J-2254D01*
G03X840299Y82796I-400J-14D01*
G02X841600Y85137I-1300J2254D01*
G37*
G36*
G01X900343Y90059D02*
G03X899759Y89829I-201J-346D01*
G02X898711Y92485I-2204J665D01*
G03X899295Y92715I201J346D01*
G02X900343Y90059I2204J-665D01*
G37*
G36*
G01X892236Y102613D02*
G03X892231Y102022I267J-298D01*
G02X889017Y97950I-1771J-1907D01*
G03X888490Y97874I-221J-333D01*
G02X885059Y101717I-1990J1676D01*
G03Y102383I-222J333D01*
G02X888233Y106490I1440J2167D01*
G03X888765I266J299D01*
G02X892236Y102613I1734J-1940D01*
G37*
G36*
G01X348832Y99110D02*
G03X348166I-333J-222D01*
G02Y101990I-2167J1440D01*
G03X348832I333J222D01*
G02X353166I2167J-1440D01*
G03X353832I333J222D01*
G02X358166I2167J-1440D01*
G03X358832I333J222D01*
G02Y99110I2167J-1440D01*
G03X358166I-333J-222D01*
G02X353832I-2167J1440D01*
G03X353166I-333J-222D01*
G02X348832I-2167J1440D01*
G37*
G36*
G01X900889Y108905D02*
G03X900609I-140J-143D01*
G02Y112195I-1610J1645D01*
G03X900889I140J143D01*
G02Y108905I1610J-1645D01*
G37*
G36*
G01X350049Y111327D02*
G03X349449I-300J-264D01*
G02Y114773I-1950J1723D01*
G03X350049I300J264D01*
G02X353949I1950J-1723D01*
G03X354549I300J264D01*
G02X358449I1950J-1723D01*
G03X359049I300J264D01*
G02Y111327I1950J-1723D01*
G03X358449I-300J-264D01*
G02X354549I-1950J1723D01*
G03X353949I-300J-264D01*
G02X350049I-1950J1723D01*
G37*
G36*
G01X117387Y128313D02*
G03Y127710I262J-301D01*
G02X114365I-1511J-1737D01*
G03Y128313I-262J302D01*
G02X117387I1511J1737D01*
G37*
G36*
G01X88391Y128814D02*
G03X88346Y128249I259J-305D01*
G02X85107Y128503I-1747J-1499D01*
G03X85152Y129068I-259J305D01*
G02X88391Y128814I1747J1499D01*
G37*
G36*
G01X756265Y152610D02*
G03X755733I-266J-299D01*
G02X752276Y156500I-1734J1940D01*
G03Y157100I-264J300D01*
G02X755733Y160990I1723J1950D01*
G03X756265I266J299D01*
G02X759722Y157100I1734J-1940D01*
G03Y156500I264J-300D01*
G02X756265Y152610I-1723J-1950D01*
G37*
G36*
G01X818719Y275406D02*
X818733Y275381D01*
X821102Y273012D01*
Y264335D01*
G03X821590Y263945I400J0D01*
G02X824310Y261054I510J-2245D01*
G01X824302Y261027D01*
Y249412D01*
X860902Y212812D01*
Y173636D01*
X868581Y165957D01*
X868606Y165943D01*
G02X869080Y162249I-1106J-2019D01*
G03X869091Y161657I274J-291D01*
G02X866930Y157714I-1515J-1733D01*
G01X866903Y157722D01*
X866062D01*
X853298Y170486D01*
Y209662D01*
X816698Y246262D01*
Y271188D01*
X815619Y272267D01*
X815594Y272281D01*
G02X818719Y275406I1106J2019D01*
G37*
G36*
G01X230265Y176110D02*
G03X229733I-266J-299D01*
G02X226276Y180000I-1734J1940D01*
G03Y180600I-264J300D01*
G02Y184500I1723J1950D01*
G03Y185100I-264J300D01*
G02X226365Y189075I1723J1950D01*
G03X226299Y189741I-251J311D01*
G02X229449Y193773I1200J2309D01*
G03X230049I300J264D01*
G02X233439Y189883I1950J-1723D01*
G03Y189217I222J-333D01*
G02X233722Y185100I-1440J-2167D01*
G03Y184500I264J-300D01*
G02Y180600I-1723J-1950D01*
G03Y180000I264J-300D01*
G02X230265Y176110I-1723J-1950D01*
G37*
G36*
G01X218678Y192845D02*
X218770Y192838D01*
X291572Y265641D01*
Y293141D01*
X291711Y293279D01*
X291704Y293371D01*
G02X294575Y291321I2295J179D01*
G01X294426Y291283D01*
Y264459D01*
X220787Y190821D01*
X220794Y190729D01*
G02X218678Y192845I-2295J-179D01*
G37*
G36*
G01X151646Y241896D02*
G03Y241337I286J-280D01*
G02X148352I-1647J-1608D01*
G03Y241896I-286J279D01*
G02X151646I1647J1608D01*
G37*
G36*
G01X879725Y242270D02*
G03Y241711I286J-279D01*
G02X876431I-1647J-1608D01*
G03Y242270I-286J280D01*
G02X879725I1647J1608D01*
G37*
G36*
G01X124189Y251243D02*
G03X124221Y250960I156J-126D01*
G02X121007Y250595I-1422J-1810D01*
G03X120975Y250878I-156J126D01*
G02X124189Y251243I1422J1810D01*
G37*
G36*
G01X849475Y251698D02*
G03X849747Y251693I139J144D01*
G02X849681Y248316I1531J-1719D01*
G03X849409Y248321I-139J-144D01*
G02X849475Y251698I-1531J1719D01*
G37*
G36*
G01X798596Y296621D02*
G03Y296021I264J-300D01*
G02X795150I-1723J-1950D01*
G03Y296621I-264J300D01*
G02Y300521I1723J1950D01*
G03Y301121I-264J300D01*
G02Y305021I1723J1950D01*
G03Y305621I-264J300D01*
G02X798596I1723J1950D01*
G03Y305021I264J-300D01*
G02Y301121I-1723J-1950D01*
G03Y300521I264J-300D01*
G02Y296621I-1723J-1950D01*
G37*
G36*
G01X281721Y297664D02*
G03Y297064I264J-300D01*
G02X278275I-1723J-1950D01*
G03Y297664I-264J300D01*
G02Y301564I1723J1950D01*
G03Y302164I-264J300D01*
G02Y306064I1723J1950D01*
G03Y306664I-264J300D01*
G02X281721I1723J1950D01*
G03Y306064I264J-300D01*
G02Y302164I-1723J-1950D01*
G03Y301564I264J-300D01*
G02Y297664I-1723J-1950D01*
G37*
G36*
G01X754057Y312384D02*
G03X753530Y312308I-221J-333D01*
G02X749607Y315727I-1991J1676D01*
G03X749602Y316269I-297J268D01*
G02X752633Y320392I1897J1781D01*
G03X753146Y320538I175J360D01*
G02X757083Y317211I2200J-1390D01*
G03X757103Y316599I267J-298D01*
G02X754057Y312384I-1603J-2050D01*
G37*
G36*
G01X556229Y328457D02*
G03X556220Y329051I-272J293D01*
G02X556083Y332840I1713J1959D01*
G03X556105Y333378I-284J281D01*
G02X559949Y333220I1994J1672D01*
G03X559927Y332682I284J-281D01*
G02X559703Y329103I-1994J-1672D01*
G03X559712Y328509I272J-293D01*
G02X559939Y324816I-1713J-1959D01*
G03Y324284I299J-266D01*
G02X556059I-1940J-1734D01*
G03Y324816I-299J266D01*
G02X556229Y328457I1940J1734D01*
G37*
G36*
G01X330309Y797799D02*
G03X330551Y798480I-41J398D01*
G01X329770Y799262D01*
X329678Y799255D01*
G02X331794Y801371I-179J2295D01*
G01X331787Y801279D01*
X408851Y724216D01*
X769296D01*
X769356Y724285D01*
G02Y721293I1749J-1496D01*
G01X769296Y721362D01*
X752859D01*
G03X752478Y720841I0J-400D01*
G02X751696Y718077I-2479J-791D01*
G03X751629Y717544I261J-303D01*
G02X747737Y714135I-2130J-1494D01*
G03X747138Y714068I-270J-295D01*
G02X743517Y717689I-2139J1482D01*
G03X743584Y718288I-228J329D01*
G02X743020Y720841I1915J1762D01*
G03X742639Y721362I-381J121D01*
G01X407669D01*
X333033Y795998D01*
X332827Y795791D01*
X332834Y795699D01*
G02X332835Y795330I-2294J-191D01*
G01X332828Y795238D01*
X343576Y784491D01*
Y730410D01*
X373807Y700179D01*
G03X374372I282J283D01*
G02X377748Y700046I1626J-1629D01*
G01X377808Y699976D01*
X749084D01*
X749709Y699352D01*
X755277D01*
X765027Y709102D01*
X766114D01*
X780370Y723358D01*
G03Y723923I-283J282D01*
G02X783591Y727213I1629J1627D01*
G03X784150Y727219I276J289D01*
G01X789711Y732779D01*
X789704Y732871D01*
G02X789713Y733320I2295J179D01*
G03X789269Y733764I-397J47D01*
G02X791285Y735780I-270J2286D01*
G03X791729Y735336I397J-47D01*
G02X791820Y730755I270J-2286D01*
G01X791728Y730762D01*
X785250Y724284D01*
Y724203D01*
X767296Y706248D01*
X766209D01*
X756459Y696498D01*
X748527D01*
X747902Y697124D01*
X377808D01*
X377748Y697054D01*
G02X377628Y696923I-1756J1488D01*
G03Y696358I283J-282D01*
G01X409665Y664320D01*
X466827D01*
X769756Y361391D01*
G03X770364Y361441I283J283D01*
G02X770538Y361658I2114J-1517D01*
G03Y362190I-299J266D01*
G02X774428Y365647I1940J1734D01*
G03X775028I300J264D01*
G02X778928I1950J-1723D01*
G03X779528I300J264D01*
G02X783931Y363055I1950J-1723D01*
G03X784330Y362522I377J-134D01*
G02X786201Y357974I148J-2598D01*
G03Y357374I264J-300D01*
G02X782755I-1723J-1950D01*
G03Y357974I-264J300D01*
G02X782025Y360793I1723J1950D01*
G03X781626Y361326I-377J134D01*
G02X779528Y362201I-148J2598D01*
G03X778928I-300J-264D01*
G02X775028I-1950J1723D01*
G03X774428I-300J-264D01*
G02X774418Y362190I-1930J1745D01*
G03Y361658I299J-266D01*
G02X773995Y357810I-1940J-1734D01*
G03X773945Y357202I233J-325D01*
G01X794750Y336397D01*
Y331703D01*
X784671Y321624D01*
X774308D01*
X774248Y321554D01*
G02X771069Y324854I-1750J1496D01*
G03X771124Y325427I-249J313D01*
G02X774303Y325120I1749J1497D01*
G03X774248Y324547I249J-313D01*
G01X774308Y324476D01*
X783489D01*
X789870Y330858D01*
G03Y331423I-283J283D01*
G02X789229Y332668I1629J1626D01*
G01X789218Y332731D01*
X574076Y547874D01*
X373808D01*
X373748Y547804D01*
G02Y550796I-1749J1496D01*
G01X373808Y550726D01*
X575258D01*
X787806Y338178D01*
G03X788372I283J283D01*
G02X788506Y338302I1629J-1626D01*
G01X788512Y338307D01*
X788659Y338454D01*
X465645Y661468D01*
X408483D01*
X340722Y729228D01*
Y783309D01*
X330811Y793221D01*
X330719Y793214D01*
G02X330309Y797799I-179J2295D01*
G37*
G36*
G01X328188Y335890D02*
G03Y335618I147J-136D01*
G02X324810I-1689J-1564D01*
G03Y335890I-147J136D01*
G02X328188I1689J1564D01*
G37*
G36*
G01X283436Y336960D02*
G03X283156Y336952I-136J-147D01*
G02X283062Y340240I-1657J1598D01*
G03X283342Y340248I136J147D01*
G02X283436Y336960I1657J-1598D01*
G37*
G36*
G01X292264Y350174D02*
G03X291732I-266J-299D01*
G02X288275Y354064I-1734J1940D01*
G03Y354664I-264J300D01*
G02Y358564I1723J1950D01*
G03Y359164I-264J300D01*
G02X291732Y363054I1723J1950D01*
G03X292264I266J299D01*
G02X295721Y359164I1734J-1940D01*
G03Y358564I264J-300D01*
G02Y354664I-1723J-1950D01*
G03Y354064I264J-300D01*
G02X292264Y350174I-1723J-1950D01*
G37*
G36*
G01X346269Y407825D02*
X346329Y407756D01*
X398690D01*
X398750Y407825D01*
G02Y404833I1749J-1496D01*
G01X398690Y404902D01*
X346329D01*
X346269Y404833D01*
G02Y407825I-1749J1496D01*
G37*
G36*
G01X129939Y423316D02*
G03Y422784I299J-266D01*
G02X126059I-1940J-1734D01*
G03Y423316I-299J266D01*
G02X126276Y427000I1940J1734D01*
G03Y427600I-264J300D01*
G02X129722I1723J1950D01*
G03Y427000I264J-300D01*
G02X129939Y423316I-1723J-1950D01*
G37*
G36*
G01X142774Y425633D02*
G03Y424967I221J-333D01*
G02X140224I-1275J-1917D01*
G03Y425633I-221J333D01*
G02X142774I1275J1917D01*
G37*
G36*
G01X182114Y436757D02*
G03X181534I-290J-276D01*
G02X177874Y440452I-1885J1793D01*
G03X177920Y440985I-273J292D01*
G02X178276Y444500I2079J1565D01*
G03Y445100I-264J300D01*
G02X181733Y448990I1723J1950D01*
G03X182265I266J299D01*
G02X185722Y445100I1734J-1940D01*
G03Y444500I264J-300D01*
G02X185939Y440816I-1723J-1950D01*
G03Y440284I299J-266D01*
G02X182114Y436757I-1940J-1734D01*
G37*
G36*
G01X28238Y441132D02*
G03X28229Y440861I142J-140D01*
G02X24853Y440967I-1737J-1511D01*
G03X24862Y441238I-142J140D01*
G02X28238Y441132I1737J1511D01*
G37*
G36*
G01X96145Y443725D02*
G03X95545Y443691I-285J-281D01*
G02X91681Y447160I-2045J1608D01*
G03X91640Y447766I-280J285D01*
G02X95149Y451573I1560J2083D01*
G03X95749I300J264D01*
G02X99636Y448113I1950J-1723D01*
G03X99676Y447540I298J-267D01*
G02X96145Y443725I-1676J-1990D01*
G37*
G36*
G01X64189Y472785D02*
G03Y472513I147J-136D01*
G02X60811Y472507I-1686J-1567D01*
G03Y472779I-147J136D01*
G02X64189Y472785I1686J1567D01*
G37*
G36*
G01X187593Y486766D02*
G03X187919Y487211I-71J394D01*
G02X188914Y489614I2580J339D01*
G03X189008Y490147I-243J318D01*
G02X188781Y490588I2189J1406D01*
G03X188524Y490701I-186J-74D01*
G02X189727Y493940I-825J2149D01*
G03X189995Y493857I176J94D01*
G02X193546Y492674I1204J-2307D01*
G03X194052Y492474I361J172D01*
G02X193699Y487796I947J-2424D01*
G03X193100Y487463I-199J-347D01*
G02X190674Y484954I-2601J87D01*
G03X190302Y484547I28J-399D01*
G02X187593Y486766I-2302J-47D01*
G37*
G36*
G01X64714Y488008D02*
G03X64707Y487736I143J-140D01*
G02X61331Y487825I-1729J-1519D01*
G03X61338Y488097I-143J140D01*
G02X64714Y488008I1729J1519D01*
G37*
G36*
G01X138679Y497191D02*
G03X138119I-280J-286D01*
G02Y500909I-1820J1859D01*
G03X138679I280J286D01*
G02Y497191I1820J-1859D01*
G37*
G36*
G01X28046Y504133D02*
G03Y503574I286J-280D01*
G02X24752I-1647J-1608D01*
G03Y504133I-286J279D01*
G02X28046I1647J1608D01*
G37*
G36*
G01X151549Y500827D02*
G03X150949I-300J-264D01*
G02Y504273I-1950J1723D01*
G03X151549I300J264D01*
G02Y500827I1950J-1723D01*
G37*
G36*
G01X38146Y519942D02*
G03Y519383I286J-279D01*
G02X34852I-1647J-1608D01*
G03Y519942I-286J279D01*
G02X38146I1647J1608D01*
G37*
G36*
G01X87846Y534417D02*
G03Y533858I286J-279D01*
G02X84552I-1647J-1608D01*
G03Y534417I-286J279D01*
G02X87846I1647J1608D01*
G37*
G36*
G01X61690Y535988D02*
G03Y535716I147J-136D01*
G02X58312Y535712I-1687J-1566D01*
G03Y535984I-147J136D01*
G02X61690Y535988I1687J1566D01*
G37*
G36*
G01X107836Y541511D02*
G03X107564I-136J-147D01*
G02Y544889I-1564J1689D01*
G03X107836I136J147D01*
G02Y541511I1564J-1689D01*
G37*
G36*
G01X32177Y555933D02*
G03X31912Y555870I-99J-174D01*
G02X31129Y559155I-1913J1280D01*
G03X31394Y559218I99J174D01*
G02X31903Y559762I1913J-1280D01*
G03X31961Y560341I-244J317D01*
G02X35103Y560026I1738J1509D01*
G03X35045Y559447I244J-317D01*
G02X32177Y555933I-1739J-1508D01*
G37*
G36*
G01X142633Y564023D02*
G03X142579Y563416I231J-326D01*
G02X139607Y563677I-1639J-1616D01*
G03X139661Y564284I-231J326D01*
G02X142633Y564023I1639J1616D01*
G37*
G36*
G01X815219Y677006D02*
X815233Y676981D01*
X819602Y672612D01*
Y666935D01*
G03X820090Y666545I400J0D01*
G02X822810Y663654I510J-2245D01*
G01X822802Y663627D01*
Y628777D01*
X878827Y572752D01*
X879077D01*
X879104Y572760D01*
G02X880534Y568385I646J-2210D01*
G03X880387Y567727I136J-376D01*
G01X881031Y567083D01*
X881056Y567069D01*
G02X877931Y563944I-1106J-2019D01*
G01X877917Y563969D01*
X876738Y565148D01*
X875677D01*
X815198Y625627D01*
Y670788D01*
X812119Y673867D01*
X812094Y673881D01*
G02X815219Y677006I1106J2019D01*
G37*
G36*
G01X30438Y595039D02*
G03X30446Y594767I151J-132D01*
G02X27070Y594660I-1638J-1617D01*
G03X27062Y594932I-151J132D01*
G02X30438Y595039I1638J1617D01*
G37*
G36*
G01X33519Y605833D02*
G03X33567Y605562I167J-110D01*
G02X30279Y604979I-1367J-1852D01*
G03X30231Y605250I-167J110D01*
G02X33519Y605833I1367J1852D01*
G37*
G36*
G01X552537Y617750D02*
G03X552563Y618311I-271J294D01*
G02X552776Y622000I1936J1739D01*
G03Y622600I-264J300D01*
G02X556319Y626409I1723J1950D01*
G03X556879I280J286D01*
G02X560517Y622689I1819J-1860D01*
G03X560518Y622115I279J-287D01*
G02X560475Y618334I-1809J-1870D01*
G03X560447Y617775I271J-294D01*
G02X556774Y614102I-1948J-1725D01*
G03X556215Y614074I-265J-299D01*
G02X552537Y617750I-1911J1766D01*
G37*
G36*
G01X29195Y622300D02*
G03Y621760I295J-270D01*
G02X25803I-1696J-1557D01*
G03Y622300I-295J270D01*
G02X29195I1696J1557D01*
G37*
G36*
G01X41714Y627895D02*
G03X41963Y627785I184J79D01*
G02X40595Y624696I746J-2178D01*
G03X40346Y624806I-184J-79D01*
G02X41714Y627895I-746J2178D01*
G37*
G36*
G01X322794Y797871D02*
X322787Y797779D01*
X337050Y783516D01*
Y690216D01*
X394378Y632888D01*
X394470Y632895D01*
G02X392354Y630779I179J-2295D01*
G01X392361Y630871D01*
X334198Y689034D01*
Y782334D01*
X320770Y795762D01*
X320678Y795755D01*
G02X322794Y797871I-179J2295D01*
G37*
G36*
G01X127188Y637386D02*
G03Y637114I147J-136D01*
G02X123810I-1689J-1564D01*
G03Y637386I-147J136D01*
G02X127188I1689J1564D01*
G37*
G36*
G01X28264Y638047D02*
G03Y637507I295J-270D01*
G02X24872I-1696J-1557D01*
G03Y638047I-295J270D01*
G02X28264I1696J1557D01*
G37*
G36*
G01X880243Y647740D02*
G03Y647181I286J-279D01*
G02X876949I-1647J-1608D01*
G03Y647740I-286J279D01*
G02X880243I1647J1608D01*
G37*
G36*
G01X849639Y653715D02*
G03X849367Y653710I-133J-149D01*
G02X849305Y657087I-1595J1660D01*
G03X849577Y657092I133J149D01*
G02X849639Y653715I1595J-1660D01*
G37*
G36*
G01X52038Y697691D02*
G03X52047Y697419I151J-131D01*
G02X48672Y697310I-1637J-1618D01*
G03X48663Y697582I-151J131D01*
G02X52038Y697691I1637J1618D01*
G37*
G36*
G01X808462Y699826D02*
G03X808485Y699186I251J-311D01*
G02X805368Y699077I-1486J-2136D01*
G03X805345Y699717I-251J311D01*
G02X805391Y704020I1486J2136D01*
G03Y704686I-222J333D01*
G02Y709020I1440J2167D01*
G03Y709686I-222J333D01*
G02X808271I1440J2167D01*
G03Y709020I222J-333D01*
G02Y704686I-1440J-2167D01*
G03Y704020I222J-333D01*
G02X808462Y699826I-1440J-2167D01*
G37*
G36*
G01X796054Y700903D02*
G03Y700303I264J-300D01*
G02X792608I-1723J-1950D01*
G03Y700903I-264J300D01*
G02Y704803I1723J1950D01*
G03Y705403I-264J300D01*
G02Y709303I1723J1950D01*
G03Y709903I-264J300D01*
G02X796054I1723J1950D01*
G03Y709303I264J-300D01*
G02Y705403I-1723J-1950D01*
G03Y704803I264J-300D01*
G02Y700903I-1723J-1950D01*
G37*
G36*
G01X282939Y703816D02*
G03Y703284I299J-266D01*
G02X279059I-1940J-1734D01*
G03Y703816I-299J266D01*
G02X282939I1940J1734D01*
G37*
G36*
G01X282675Y715559D02*
G03X282599Y715032I257J-306D01*
G02X278757Y715581I-2166J-1442D01*
G03X278833Y716108I-257J306D01*
G02X282675Y715559I2166J1442D01*
G37*
G36*
G01X329501Y742557D02*
G03X329521Y742277I152J-130D01*
G02X326247Y742043I-1522J-1727D01*
G03X326227Y742323I-152J130D01*
G02X329501Y742557I1522J1727D01*
G37*
G36*
G01X283935Y743361D02*
G03X283663I-136J-147D01*
G02Y746739I-1564J1689D01*
G03X283935I136J147D01*
G02Y743361I1564J-1689D01*
G37*
G36*
G01X784919Y758432D02*
G03Y757832I264J-300D01*
G02X781473I-1723J-1950D01*
G03Y758432I-264J300D01*
G02X780743Y761251I1723J1950D01*
G03X780344Y761784I-377J134D01*
G02X778246Y762659I-148J2598D01*
G03X777646I-300J-264D01*
G02X773746I-1950J1723D01*
G03X773146I-300J-264D01*
G02X773136Y762648I-1930J1745D01*
G03Y762116I299J-266D01*
G02X769256I-1940J-1734D01*
G03Y762648I-299J266D01*
G02X773146Y766105I1940J1734D01*
G03X773746I300J264D01*
G02X777646I1950J-1723D01*
G03X778246I300J264D01*
G02X782649Y763513I1950J-1723D01*
G03X783048Y762980I377J-134D01*
G02X784919Y758432I148J-2598D01*
G37*
G36*
G01X309320Y759226D02*
G03X309873Y759058I357J181D01*
G02X309060Y755809I1126J-2008D01*
G03X308494Y755920I-336J-216D01*
G02X309320Y759226I-1495J2130D01*
G37*
G36*
G01X293265Y756110D02*
G03X292733I-266J-299D01*
G02X289276Y760000I-1734J1940D01*
G03Y760600I-264J300D01*
G02Y764500I1723J1950D01*
G03Y765100I-264J300D01*
G02X292733Y768990I1723J1950D01*
G03X293265I266J299D01*
G02X296722Y765100I1734J-1940D01*
G03Y764500I264J-300D01*
G02Y760600I-1723J-1950D01*
G03Y760000I264J-300D01*
G02X293265Y756110I-1723J-1950D01*
G37*
G36*
G01X112616Y797635D02*
G03X112542Y797080I246J-315D01*
G02X109284Y797515I-1842J-1380D01*
G03X109358Y798070I-246J315D01*
G02X109351Y800821I1842J1380D01*
G03X109291Y801361I-322J238D01*
G02X109300Y804846I1509J1739D01*
G03X109323Y805126I-130J152D01*
G02X109455Y808225I1766J1477D01*
G03X109465Y808496I-142J141D01*
G02X109470Y811512I1742J1505D01*
G03X109461Y811783I-151J131D01*
G02X112837Y811889I1639J1617D01*
G03X112846Y811618I151J-131D01*
G02X112841Y808379I-1639J-1617D01*
G03X112831Y808108I142J-141D01*
G02X112589Y804857I-1742J-1505D01*
G03X112566Y804577I130J-152D01*
G02X112649Y801729I-1766J-1477D01*
G03X112709Y801189I322J-238D01*
G02X112616Y797635I-1509J-1739D01*
G37*
G36*
G01X167718Y814028D02*
G03X167184Y813982I-242J-319D01*
G02X166887Y817387I-1685J1568D01*
G03X167421Y817433I242J319D01*
G02X167718Y814028I1685J-1568D01*
G37*
G36*
G01X207114Y836257D02*
G03X206534I-290J-276D01*
G02X202733Y839811I-1885J1793D01*
G03Y840352I-294J271D01*
G02X202644Y843771I1916J1761D01*
G03X202624Y844304I-308J255D01*
G02X206447Y847832I1872J1807D01*
G03X207047Y847833I300J265D01*
G02X210934Y844373I1953J-1720D01*
G03X210932Y843840I298J-268D01*
G02X210907Y840358I-1946J-1727D01*
G03X210909Y839817I296J-269D01*
G02X207114Y836257I-1910J-1767D01*
G37*
G36*
G01X157821Y861193D02*
G03Y860907I140J-143D01*
G02X154059Y860784I-1822J-1857D01*
G03Y861316I-299J266D01*
G02X157733Y864990I1940J1734D01*
G03X158265I266J299D01*
G02X161733I1734J-1940D01*
G03X162265I266J299D01*
G02Y861110I1734J-1940D01*
G03X161733I-266J-299D01*
G02X158142Y861228I-1734J1940D01*
G03X157856I-143J-140D01*
G02X157821Y861193I-1857J1822D01*
G37*
G36*
G01X370004Y882349D02*
X370074Y882409D01*
Y887909D01*
X366909Y891074D01*
X226140D01*
G03X225857Y890391I0J-400D01*
G01X227200Y889048D01*
Y883552D01*
X223997Y880348D01*
X204501D01*
X157501Y927348D01*
X151501D01*
X147798Y931052D01*
Y937048D01*
X150001Y939252D01*
X162681D01*
X162714Y939264D01*
G02X164349Y939240I786J-2164D01*
G01X164385Y939226D01*
X166724D01*
X169393Y936556D01*
X169534Y936687D01*
G02X169784Y936889I1568J-1685D01*
G03X169769Y937555I-229J328D01*
G02X172316Y937611I1231J1945D01*
G03X172331Y936945I229J-328D01*
G02X173097Y933855I-1231J-1945D01*
G03X173169Y933583I173J-100D01*
G02X174299Y931723I-1169J-1983D01*
G01X174303Y931646D01*
X209641Y896308D01*
G03X210194Y896296I283J283D01*
G02X214045Y894421I1556J-1696D01*
G01X214038Y894329D01*
X214441Y893926D01*
X368091D01*
X372926Y889091D01*
Y882409D01*
X372996Y882349D01*
G02X370004I-1496J-1749D01*
G37*
G36*
G01X156939Y893883D02*
G03Y893217I222J-333D01*
G02X154059I-1440J-2167D01*
G03Y893883I-222J333D01*
G02X156941Y898216I1441J2167D01*
G03X157468Y898292I221J333D01*
G02X161241Y898512I1991J-1676D01*
G03X161780Y898503I274J291D01*
G02X161717Y894654I1719J-1953D01*
G03X161178Y894663I-274J-291D01*
G02X158017Y894450I-1719J1953D01*
G03X157490Y894374I-221J-333D01*
G02X156939Y893883I-1989J1678D01*
G37*
G36*
G01X159222Y907100D02*
G03Y906500I264J-300D01*
G02X155776I-1723J-1950D01*
G03Y907100I-264J300D01*
G02X159222I1723J1950D01*
G37*
G36*
G01X217549Y924890D02*
G03X216949I-300J-264D01*
G02Y928336I-1950J1723D01*
G03X217549I300J264D01*
G02Y924890I1950J-1723D01*
G37*
G36*
G01X110639Y930215D02*
G03X110659Y929942I156J-126D01*
G02X107305Y929692I-1560J-1692D01*
G03X107285Y929965I-156J126D01*
G02X110639Y930215I1560J1692D01*
G37*
G36*
G01X217549Y937890D02*
G03X216949I-300J-264D01*
G02X213276Y941563I-1950J1723D01*
G03Y942163I-264J300D01*
G02Y946063I1723J1950D01*
G03Y946663I-264J300D01*
G02X216949Y950336I1723J1950D01*
G03X217549I300J264D01*
G02X221062Y946533I1950J-1723D01*
G03Y945893I240J-320D01*
G02X221358Y941993I-1563J-2080D01*
G03Y941433I286J-280D01*
G02X217549Y937890I-1859J-1820D01*
G37*
G36*
G01X232045Y1074110D02*
G02X232010Y1072954I-2245J-511D01*
G01X232002Y1072927D01*
Y1068569D01*
G03X232564Y1068203I400J-1D01*
G02Y1063997I936J-2103D01*
G03X232002Y1063631I-162J-365D01*
G01Y1060081D01*
G03X232684Y1059798I400J0D01*
G01X239967Y1067081D01*
X239981Y1067106D01*
G02X243106Y1063981I2019J-1106D01*
G01X243081Y1063967D01*
X235202Y1056088D01*
Y1041988D01*
X159261Y966048D01*
X155422D01*
X155395Y966039D01*
G02Y970459I-646J2210D01*
G01X155422Y970450D01*
X157437D01*
X163251Y976265D01*
G03X162968Y976948I-283J283D01*
G01X155422D01*
X155395Y976939D01*
G02Y981359I-646J2210D01*
G01X155422Y981350D01*
X163811D01*
X168403Y985943D01*
G03X168120Y986625I-283J282D01*
G01X165173D01*
G02Y995028I0J4201D01*
G01X169473D01*
G02X173530Y991918I0J-4201D01*
G03X174200Y991739I387J104D01*
G01X227598Y1045138D01*
Y1072115D01*
G03X226916Y1072398I-400J0D01*
G01X224088Y1069571D01*
X224095Y1069479D01*
G02X221979Y1071595I-2295J-179D01*
G01X222071Y1071588D01*
X227909Y1077426D01*
X228178D01*
X228203Y1077452D01*
X240666D01*
X269641Y1048476D01*
X340326D01*
X340428Y1048374D01*
X340520Y1048381D01*
G02X338479Y1045476I179J-2295D01*
G01X338439Y1045624D01*
X268459D01*
X239484Y1074598D01*
X232435D01*
G03X232045Y1074110I0J-400D01*
G37*
G36*
G01X824206Y1073961D02*
G02X828010Y1071654I1594J-1661D01*
G01X828002Y1071627D01*
Y1030177D01*
X876794Y981384D01*
X882410D01*
X882437Y981393D01*
G02Y976973I646J-2210D01*
G01X882410Y976982D01*
X878698D01*
G03X878415Y976299I0J-400D01*
G01X880789Y973925D01*
X880814Y973911D01*
G02X877689Y970786I-1106J-2019D01*
G01X877675Y970811D01*
X874705Y973782D01*
X873644D01*
X820398Y1027027D01*
Y1070988D01*
X814813Y1076573D01*
X814764Y1076588D01*
G02X816046Y1081010I636J2212D01*
G01X816073Y1081002D01*
X816612D01*
X823647Y1073967D01*
G03X824206Y1073961I283J283D01*
G37*
G36*
G01X879771Y1053059D02*
G03X879793Y1052788I157J-124D01*
G02X876426Y1052521I-1560J-1693D01*
G03X876404Y1052792I-157J124D01*
G02X879771Y1053059I1560J1693D01*
G37*
G36*
G01X848791Y1063187D02*
G03X849324Y1063179I271J294D01*
G02X849275Y1059746I1509J-1738D01*
G03X848742Y1059754I-271J-294D01*
G02X848791Y1063187I-1509J1738D01*
G37*
G36*
G01X771820Y1122255D02*
X771728Y1122262D01*
X744590Y1095124D01*
X347308D01*
X347248Y1095054D01*
G02X343270Y1097124I-1749J1497D01*
G03X342882Y1097624I-388J100D01*
G01X338590D01*
X329640Y1088674D01*
X240059D01*
X232159Y1096574D01*
X223091D01*
X213641Y1087124D01*
X167861D01*
X166882Y1086144D01*
X166914Y1086031D01*
G02X164321Y1087671I-2214J-631D01*
G01X164384Y1087681D01*
X166679Y1089976D01*
X212459D01*
X221909Y1099426D01*
X233341D01*
X241241Y1091526D01*
X328458D01*
X337408Y1100476D01*
X362690D01*
X362750Y1100546D01*
G02X366728Y1098476I1749J-1497D01*
G03X367116Y1097976I388J-100D01*
G01X743408D01*
X769711Y1124279D01*
X769704Y1124371D01*
G02X771820Y1122255I2295J179D01*
G37*
G36*
G01X808507Y1108890D02*
G03X808462Y1108202I180J-357D01*
G02X808679Y1104063I-1463J-2152D01*
G03X808725Y1103419I259J-305D01*
G02X809281Y1099481I-1384J-2204D01*
G03X809302Y1098926I298J-267D01*
G02X809356Y1098872I-1812J-1867D01*
G03X809642I143J140D01*
G02X809765Y1095110I1857J-1822D01*
G03X809233I-266J-299D01*
G02X805186Y1095858I-1734J1940D01*
G03X804520Y1095927I-356J-183D01*
G02X800765Y1095626I-2021J1639D01*
G03X800233I-266J-299D01*
G02Y1099506I-1734J1940D01*
G03X800765I266J299D01*
G02X804812Y1098758I1734J-1940D01*
G03X805478Y1098689I356J183D01*
G02X805559Y1098785I2029J-1630D01*
G03X805538Y1099340I-298J267D01*
G02X805661Y1103203I1803J1876D01*
G03X805615Y1103847I-259J305D01*
G02X805833Y1108376I1384J2203D01*
G03X805878Y1109064I-180J357D01*
G02X805901Y1113383I1463J2152D01*
G03Y1114049I-222J333D01*
G02X808781I1440J2167D01*
G03Y1113383I222J-333D01*
G02X808507Y1108890I-1440J-2167D01*
G37*
G36*
G01X138779Y1126895D02*
X138871Y1126888D01*
X150109Y1138126D01*
X249691D01*
X249751Y1138196D01*
G02Y1135204I1749J-1496D01*
G01X249691Y1135274D01*
X151291D01*
X140888Y1124871D01*
X140895Y1124779D01*
G02X138779Y1126895I-2295J-179D01*
G37*
G36*
G01X262294Y1151085D02*
G03X261761Y1151077I-262J-302D01*
G02X261704Y1154957I-1762J1915D01*
G03X262237Y1154965I262J302D01*
G02X265949Y1154773I1762J-1915D01*
G03X266549I300J264D01*
G02X270233Y1154990I1950J-1723D01*
G03X270765I266J299D01*
G02Y1151110I1734J-1940D01*
G03X270233I-266J-299D01*
G02X266549Y1151327I-1734J1940D01*
G03X265949I-300J-264D01*
G02X262294Y1151085I-1950J1723D01*
G37*
G36*
G01X785056Y1159942D02*
G03Y1159342I264J-300D01*
G02X781610I-1723J-1950D01*
G03Y1159942I-264J300D01*
G02X780880Y1162761I1723J1950D01*
G03X780481Y1163294I-377J134D01*
G02X778383Y1164169I-148J2598D01*
G03X777783I-300J-264D01*
G02X773883I-1950J1723D01*
G03X773283I-300J-264D01*
G02X773273Y1164158I-1930J1745D01*
G03Y1163626I299J-266D01*
G02X769393I-1940J-1734D01*
G03Y1164158I-299J266D01*
G02X773283Y1167615I1940J1734D01*
G03X773883I300J264D01*
G02X777783I1950J-1723D01*
G03X778383I300J264D01*
G02X782786Y1165023I1950J-1723D01*
G03X783185Y1164490I377J-134D01*
G02X785056Y1159942I148J-2598D01*
G37*
G36*
G01X261765Y1159610D02*
G03X261233I-266J-299D01*
G02Y1163490I-1734J1940D01*
G03X261765I266J299D01*
G02X265449Y1163273I1734J-1940D01*
G03X266049I300J264D01*
G02X269733Y1163490I1950J-1723D01*
G03X270265I266J299D01*
G02Y1159610I1734J-1940D01*
G03X269733I-266J-299D01*
G02X266049Y1159827I-1734J1940D01*
G03X265449I-300J-264D01*
G02X261765Y1159610I-1950J1723D01*
G37*
G36*
G01X105113Y1196686D02*
G03X105719Y1196464I384J110D01*
G02X104786Y1193914I1280J-1914D01*
G03X104180Y1194136I-384J-110D01*
G02X105113Y1196686I-1280J1914D01*
G37*
G36*
G01X146614Y1220320D02*
G03X146034I-290J-276D01*
G02X142209Y1223847I-1885J1793D01*
G03Y1224379I-299J266D01*
G02Y1227847I1940J1734D01*
G03Y1228379I-299J266D01*
G02X146029Y1231912I1940J1735D01*
G03X146606I288J277D01*
G02X150432Y1228386I1879J-1800D01*
G03X150434Y1227853I299J-265D01*
G02X150439Y1224379I-1935J-1740D01*
G03Y1223847I299J-266D01*
G02X146614Y1220320I-1940J-1734D01*
G37*
G36*
G01X108178Y1310008D02*
X108270Y1310001D01*
X109670Y1311402D01*
X123172D01*
G03X123455Y1312084I0J400D01*
G01X120778Y1314762D01*
X120686Y1314755D01*
G02X122802Y1316871I-179J2295D01*
G01X122795Y1316779D01*
X125598Y1313976D01*
X156008D01*
X166508Y1324476D01*
X367740D01*
X369878Y1322338D01*
X369970Y1322345D01*
G02X367854Y1320229I179J-2295D01*
G01X367861Y1320321D01*
X366558Y1321624D01*
X167690D01*
X158151Y1312084D01*
G03X158434Y1311401I283J-283D01*
G01X341333D01*
X341408Y1311476D01*
X343615D01*
X343675Y1311546D01*
G02Y1308554I1749J-1496D01*
G01X343615Y1308624D01*
X342590D01*
X342515Y1308548D01*
X182146D01*
G03X181860Y1307869I0J-400D01*
G02X181722Y1304100I-1861J-1819D01*
G03Y1303500I264J-300D01*
G02X181480Y1299410I-1723J-1950D01*
G03Y1298753I227J-328D01*
G02X181915Y1294852I-1481J-2140D01*
G03Y1294311I294J-270D01*
G02X178049Y1290827I-1916J-1761D01*
G03X177449I-300J-264D01*
G02X173937Y1294631I-1950J1723D01*
G03X173980Y1295233I-240J320D01*
G02X174280Y1299165I1843J1837D01*
G03X174237Y1299837I-237J322D01*
G02X173559Y1303847I1262J2276D01*
G03Y1304379I-299J266D01*
G02X173587Y1307877I1940J1734D01*
G03X173293Y1308548I-294J271D01*
G01X110852D01*
X110287Y1307984D01*
X110294Y1307892D01*
G02X108178Y1310008I-2295J-179D01*
G37*
G36*
G01X294821Y1510705D02*
X294729Y1510712D01*
X292926Y1508909D01*
Y1447909D01*
X206491Y1361474D01*
X200958D01*
X200898Y1361404D01*
G02Y1364396I-1749J1496D01*
G01X200958Y1364326D01*
X205309D01*
X290074Y1449091D01*
Y1510091D01*
X292712Y1512729D01*
X292705Y1512821D01*
G02X294821Y1510705I2295J179D01*
G37*
G36*
G01X816719Y1487406D02*
X816733Y1487381D01*
X821100Y1483013D01*
Y1469435D01*
G03X821589Y1469045I400J0D01*
G02X824310Y1466154I511J-2245D01*
G01X824302Y1466127D01*
Y1425312D01*
X867789Y1381824D01*
X867814Y1381811D01*
G02X868715Y1380910I-1114J-2015D01*
G01X868728Y1380885D01*
X868902Y1380712D01*
Y1380469D01*
X868910Y1380442D01*
G02X868202Y1378052I-2210J-645D01*
G03X868187Y1377460I261J-303D01*
G02X865950Y1373586I-1591J-1664D01*
G01X865923Y1373594D01*
X865262D01*
X864228Y1374628D01*
G03X863635Y1374598I-283J-283D01*
G02X860397Y1377836I-1786J1452D01*
G03X860427Y1378429I-253J310D01*
G01X816698Y1422159D01*
Y1481189D01*
X813619Y1484267D01*
X813594Y1484281D01*
G02X816719Y1487406I1106J2019D01*
G37*
G36*
G01X119037Y1428368D02*
G03Y1427809I286J-279D01*
G02X115743I-1647J-1608D01*
G03Y1428368I-286J280D01*
G02X119037I1647J1608D01*
G37*
G36*
G01X964223Y1439050D02*
G03Y1438450I264J-300D01*
G02X960777I-1723J-1950D01*
G03Y1439050I-264J300D01*
G02X964223I1723J1950D01*
G37*
G36*
G01X954523Y1440050D02*
G03Y1439450I264J-300D01*
G02X951077I-1723J-1950D01*
G03Y1440050I-264J300D01*
G02X954523I1723J1950D01*
G37*
G36*
G01X973723D02*
G03Y1439450I264J-300D01*
G02X970277I-1723J-1950D01*
G03Y1440050I-264J300D01*
G02X973723I1723J1950D01*
G37*
G36*
G01X106362Y1443086D02*
G03X106352Y1442448I236J-323D01*
G02X103572Y1442489I-1417J-1814D01*
G03X103582Y1443127I-236J323D01*
G02X106362Y1443086I1417J1814D01*
G37*
G36*
G01X963923Y1449850D02*
G03Y1449250I264J-300D01*
G02X960477I-1723J-1950D01*
G03Y1449850I-264J300D01*
G02X960760Y1453967I1723J1950D01*
G03Y1454633I-222J333D01*
G02X960477Y1458750I1440J2167D01*
G03Y1459350I-264J300D01*
G02X960816Y1463504I1723J1950D01*
G03X960790Y1464197I-212J339D01*
G02X963384Y1464296I1211J2303D01*
G03X963410Y1463603I212J-339D01*
G02X963923Y1459350I-1210J-2303D01*
G03Y1458750I264J-300D01*
G02X963640Y1454633I-1723J-1950D01*
G03Y1453967I222J-333D01*
G02X963923Y1449850I-1440J-2167D01*
G37*
G36*
G01X954223Y1450850D02*
G03Y1450250I264J-300D01*
G02X950777I-1723J-1950D01*
G03Y1450850I-264J300D01*
G02X951060Y1454967I1723J1950D01*
G03Y1455633I-222J333D01*
G02X950777Y1459750I1440J2167D01*
G03Y1460350I-264J300D01*
G02X951116Y1464504I1723J1950D01*
G03X951090Y1465197I-212J339D01*
G02X953684Y1465296I1211J2303D01*
G03X953710Y1464603I212J-339D01*
G02X954223Y1460350I-1210J-2303D01*
G03Y1459750I264J-300D01*
G02X953940Y1455633I-1723J-1950D01*
G03Y1454967I222J-333D01*
G02X954223Y1450850I-1440J-2167D01*
G37*
G36*
G01X973423D02*
G03Y1450250I264J-300D01*
G02X969977I-1723J-1950D01*
G03Y1450850I-264J300D01*
G02X970260Y1454967I1723J1950D01*
G03Y1455633I-222J333D01*
G02X969977Y1459750I1440J2167D01*
G03Y1460350I-264J300D01*
G02X970316Y1464504I1723J1950D01*
G03X970290Y1465197I-212J339D01*
G02X972884Y1465296I1211J2303D01*
G03X972910Y1464603I212J-339D01*
G02X973423Y1460350I-1210J-2303D01*
G03Y1459750I264J-300D01*
G02X973140Y1455633I-1723J-1950D01*
G03Y1454967I222J-333D01*
G02X973423Y1450850I-1440J-2167D01*
G37*
G36*
G01X144647Y1458502D02*
G03X144662Y1457965I304J-260D01*
G02X141252Y1457871I-1662J-1592D01*
G03X141237Y1458408I-304J260D01*
G02X144647Y1458502I1662J1592D01*
G37*
G36*
G01X879567Y1458454D02*
G03X879583Y1458171I149J-134D01*
G02X876340Y1457987I-1529J-1721D01*
G03X876324Y1458270I-149J134D01*
G02X879567Y1458454I1529J1721D01*
G37*
G36*
G01X125514Y1467291D02*
G03X125443Y1466671I213J-338D01*
G02X122584Y1467000I-1635J-1621D01*
G03X122655Y1467620I-213J338D01*
G02X125514Y1467291I1635J1621D01*
G37*
G36*
G01X850696Y1464683D02*
G03X850424Y1464688I-139J-144D01*
G02X850480Y1468065I-1536J1714D01*
G03X850752Y1468060I139J144D01*
G02X850696Y1464683I1536J-1714D01*
G37*
G36*
G01X952853Y1498177D02*
G03X952873Y1497510I231J-327D01*
G02X949996Y1497423I-1373J-2210D01*
G03X949976Y1498090I-231J327D01*
G02X949626Y1502250I1373J2210D01*
G03Y1502850I-264J300D01*
G02X953072I1723J1950D01*
G03Y1502250I264J-300D01*
G02X952853Y1498177I-1723J-1950D01*
G37*
G36*
G01X961553D02*
G03X961573Y1497510I231J-327D01*
G02X958696Y1497423I-1373J-2210D01*
G03X958676Y1498090I-231J327D01*
G02X958326Y1502250I1373J2210D01*
G03Y1502850I-264J300D01*
G02X961772I1723J1950D01*
G03Y1502250I264J-300D01*
G02X961553Y1498177I-1723J-1950D01*
G37*
G36*
G01X974053Y1500177D02*
G03X974073Y1499510I231J-327D01*
G02X971196Y1499423I-1373J-2210D01*
G03X971176Y1500090I-231J327D01*
G02X970826Y1504250I1373J2210D01*
G03Y1504850I-264J300D01*
G02X974272I1723J1950D01*
G03Y1504250I264J-300D01*
G02X974053Y1500177I-1723J-1950D01*
G37*
G36*
G01X810685Y1506555D02*
G03Y1505889I222J-333D01*
G02X807805I-1440J-2167D01*
G03Y1506555I-222J333D01*
G02X807597Y1510736I1440J2167D01*
G03X807565Y1511379I-253J310D01*
G02X807790Y1515854I1434J2171D01*
G03X807823Y1516543I-186J354D01*
G02X810454Y1516418I1422J2179D01*
G03X810421Y1515729I186J-354D01*
G02X810647Y1511536I-1422J-2179D01*
G03X810679Y1510893I253J-310D01*
G02X810685Y1506555I-1434J-2171D01*
G37*
G36*
G01X797439Y1507383D02*
G03Y1506717I222J-333D01*
G02X794559I-1440J-2167D01*
G03Y1507383I-222J333D01*
G02X794276Y1511500I1440J2167D01*
G03Y1512100I-264J300D01*
G02Y1516000I1723J1950D01*
G03Y1516600I-264J300D01*
G02X797722I1723J1950D01*
G03Y1516000I264J-300D01*
G02Y1512100I-1723J-1950D01*
G03Y1511500I264J-300D01*
G02X797439Y1507383I-1723J-1950D01*
G37*
G36*
G01X281222Y1513100D02*
G03Y1512500I264J-300D01*
G02X277776I-1723J-1950D01*
G03Y1513100I-264J300D01*
G02X281222I1723J1950D01*
G37*
G36*
G01X269119Y1520643D02*
G03Y1520057I273J-293D01*
G02X265579I-1770J-1907D01*
G03Y1520643I-273J293D01*
G02X265688Y1524553I1770J1907D01*
G03Y1525169I-255J308D01*
G02X269010I1661J2003D01*
G03Y1524553I255J-308D01*
G02X269119Y1520643I-1661J-2003D01*
G37*
G36*
G01X280712Y1528452D02*
G03X280779Y1527923I329J-227D01*
G02X276930Y1527430I-1704J-1966D01*
G03X276863Y1527959I-329J227D01*
G02X280712Y1528452I1704J1966D01*
G37*
G36*
G01X787550Y1563846D02*
G03Y1563246I264J-300D01*
G02X784104I-1723J-1950D01*
G03Y1563846I-264J300D01*
G02X783374Y1566665I1723J1950D01*
G03X782975Y1567198I-377J134D01*
G02X780877Y1568073I-148J2598D01*
G03X780277I-300J-264D01*
G02X776377I-1950J1723D01*
G03X775777I-300J-264D01*
G02X775524Y1567823I-1951J1722D01*
G03X775457Y1567290I261J-303D01*
G02X771630Y1567769I-2130J-1494D01*
G03X771697Y1568302I-261J303D01*
G02X775777Y1571519I2130J1494D01*
G03X776377I300J264D01*
G02X780277I1950J-1723D01*
G03X780877I300J264D01*
G02X785280Y1568927I1950J-1723D01*
G03X785679Y1568394I377J-134D01*
G02X787550Y1563846I148J-2598D01*
G37*
G36*
G01X308859Y1567965D02*
G03X308268Y1567842I-242J-318D01*
G02X307753Y1571035I-2270J1272D01*
G03X308352Y1571104I269J296D01*
G02X308859Y1567965I1897J-1304D01*
G37*
G36*
G01X197315Y1621743D02*
G03X197328Y1621130I263J-301D01*
G02X193985Y1621057I-1628J-2030D01*
G03X193972Y1621670I-263J301D01*
G02X197315Y1621743I1628J2030D01*
G37*
G36*
G01X181869Y1629104D02*
G03X181944Y1628566I328J-228D01*
G02X178163Y1628036I-1645J-2016D01*
G03X178088Y1628574I-328J228D01*
G02X178057Y1632581I1645J2016D01*
G03X178133Y1633108I-257J306D01*
G02X181975Y1632559I2166J1442D01*
G03X181899Y1632032I257J-306D01*
G02X181869Y1629104I-2166J-1442D01*
G37*
G36*
G01X133936Y1708460D02*
G03X133656Y1708452I-136J-147D01*
G02X133562Y1711740I-1657J1598D01*
G03X133842Y1711748I136J147D01*
G02X133936Y1708460I1657J-1598D01*
G37*
G36*
G01X107926Y1714174D02*
G03X108206Y1714118I167J109D01*
G02X107724Y1710747I1293J-1905D01*
G03X107440Y1710771I-154J-128D01*
G02X107926Y1714174I-1691J1978D01*
G37*
G36*
G01X141924Y1731445D02*
G03X142590Y1731318I373J145D01*
G02X142075Y1728605I1909J-1768D01*
G03X141409Y1728732I-373J-145D01*
G02X141924Y1731445I-1909J1768D01*
G37*
G36*
G01X133110Y1731900D02*
G03X132777Y1731307I17J-400D01*
G02X128525Y1731746I-2278J-1257D01*
G03X128192Y1732405I-303J260D01*
G02X130309Y1736200I-192J2595D01*
G03X130975Y1736134I355J185D01*
G02X133110Y1731900I2025J-1634D01*
G37*
G36*
G01X111003Y1741807D02*
G03X110988Y1741215I261J-303D01*
G02X107895Y1741293I-1589J-1665D01*
G03X107910Y1741885I-261J303D01*
G02X111003Y1741807I1589J1665D01*
G37*
G36*
G01X86961Y1750609D02*
G03X86949Y1750338I141J-142D01*
G02X83574Y1750484I-1755J-1490D01*
G03X83586Y1750755I-141J142D01*
G02X86961Y1750609I1755J1490D01*
G37*
G36*
G01X812603Y1880891D02*
G02X809096Y1883870I-1703J1549D01*
G03X808783Y1884518I-313J248D01*
G01X805828D01*
X804819Y1885527D01*
X804794Y1885541D01*
G02X807699Y1888997I1106J2019D01*
G01X807759Y1888922D01*
X812412D01*
X817702Y1883632D01*
Y1846886D01*
X819816Y1844772D01*
G03X820498Y1845055I282J283D01*
G01Y1870427D01*
X820490Y1870454D01*
G02X824910I2210J646D01*
G01X824902Y1870427D01*
Y1844212D01*
X880781Y1788333D01*
X880806Y1788319D01*
G02X881191Y1784546I-1106J-2019D01*
G03X881185Y1783941I259J-305D01*
G02X879018Y1780003I-1521J-1728D01*
G01X878991Y1780012D01*
X878349D01*
X813298Y1845062D01*
Y1880622D01*
G03X812603Y1880891I-400J-1D01*
G37*
G36*
G01X163655Y1791010D02*
G03X163265Y1791498I-390J88D01*
G01X163199D01*
X163149Y1791466D01*
G02X160794Y1795419I-1249J1934D01*
G01X160819Y1795433D01*
X161288Y1795902D01*
X181839D01*
X215148Y1829211D01*
Y1886562D01*
X216067Y1887481D01*
X216081Y1887506D01*
G02X219619Y1884671I2019J-1105D01*
G01X219552Y1884611D01*
Y1871481D01*
G03X220234Y1871198I400J0D01*
G01X226938Y1877902D01*
X229127D01*
X229154Y1877910D01*
G02Y1873490I646J-2210D01*
G01X229127Y1873498D01*
X228762D01*
X222752Y1867488D01*
Y1825673D01*
X185177Y1788098D01*
X165188D01*
X164819Y1788467D01*
X164794Y1788481D01*
G02X163655Y1791010I1106J2019D01*
G37*
G36*
G01X795489Y1803226D02*
G03X795261Y1803067I-32J-197D01*
G02X793360Y1805774I-2261J433D01*
G03X793588Y1805933I32J197D01*
G02X795489Y1803226I2261J-433D01*
G37*
G36*
G01X646267Y1817848D02*
G03X646443Y1817255I331J-224D01*
G02X643642Y1816423I-894J-2121D01*
G03X643466Y1817016I-331J224D01*
G02X646267Y1817848I894J2121D01*
G37*
G36*
G01X805299Y1824144D02*
G03X805579Y1824111I157J124D01*
G02X805201Y1820864I1421J-1811D01*
G03X804921Y1820897I-157J-124D01*
G02X805299Y1824144I-1421J1811D01*
G37*
G36*
G01X139695Y1863594D02*
G03Y1863054I295J-270D01*
G02X136303I-1696J-1557D01*
G03Y1863594I-295J270D01*
G02X139695I1696J1557D01*
G37*
G36*
G01X868561Y1864007D02*
G03Y1863448I286J-279D01*
G02X865267I-1647J-1608D01*
G03Y1864007I-286J280D01*
G02X868561I1647J1608D01*
G37*
G36*
G01X125186Y1872593D02*
G03X125170Y1872322I139J-144D01*
G02X121799Y1872520I-1777J-1463D01*
G03X121815Y1872791I-139J144D01*
G02X125186Y1872593I1777J1463D01*
G37*
G36*
G01X851925Y1869356D02*
G03X851653Y1869358I-137J-146D01*
G02X851673Y1872736I-1554J1698D01*
G03X851945Y1872734I137J146D01*
G02X851925Y1869356I1554J-1698D01*
G37*
G36*
G01X229671Y1888873D02*
G03X230261Y1888812I323J237D01*
G02X229943Y1885740I1539J-1712D01*
G03X229353Y1885801I-323J-237D01*
G02X229671Y1888873I-1539J1712D01*
G37*
G36*
G01X81265Y1885610D02*
G03X80733I-266J-299D01*
G02X77059Y1889284I-1734J1940D01*
G03Y1889816I-299J266D01*
G02X77276Y1893500I1940J1734D01*
G03Y1894100I-264J300D01*
G02X76833Y1897492I1723J1950D01*
G03X76757Y1898019I-333J221D01*
G02X76788Y1902026I1676J1991D01*
G03X76863Y1902564I-253J310D01*
G02X80936Y1905787I2136J1486D01*
G03X81527Y1905782I298J267D01*
G02X85599Y1902568I1907J-1771D01*
G03X85675Y1902041I333J-221D01*
G02X85696Y1898077I-1676J-1991D01*
G03X85629Y1897544I261J-303D01*
G02X84981Y1893911I-2130J-1494D01*
G03X84914Y1893312I228J-329D01*
G02X84939Y1889816I-1915J-1762D01*
G03Y1889284I299J-266D01*
G02X81265Y1885610I-1940J-1734D01*
G37*
G36*
G01X127594Y1907557D02*
G03X126852Y1907552I-370J-152D01*
G02X122788Y1910526I-2419J958D01*
G03X122863Y1911064I-253J310D01*
G02X126936Y1914287I2136J1486D01*
G03X127527Y1914282I298J267D01*
G02X131599Y1911068I1907J-1771D01*
G03X131675Y1910541I333J-221D01*
G02X127594Y1907557I-1676J-1991D01*
G37*
G36*
G01X793556Y1915433D02*
G03X793557Y1915966I-298J267D01*
G02X793709Y1919582I1944J1729D01*
G03X793708Y1920162I-276J290D01*
G02X797291Y1920164I1790J1888D01*
G03X797292Y1919584I276J-290D01*
G02X797438Y1915959I-1791J-1888D01*
G03X797437Y1915426I298J-267D01*
G02X797448Y1911978I-1944J-1730D01*
G03X797452Y1911446I300J-264D01*
G02X793571Y1911414I-1926J-1750D01*
G03X793567Y1911946I-300J264D01*
G02X793556Y1915433I1926J1750D01*
G37*
G36*
G01X809659Y1912915D02*
G03Y1912315I264J-300D01*
G02X806213I-1723J-1950D01*
G03Y1912915I-264J300D01*
G02X806026Y1916632I1723J1950D01*
G03X806035Y1917165I-294J272D01*
G02X806061Y1920595I1970J1700D01*
G03X806060Y1921128I-299J266D01*
G02X809941Y1921135I1937J1737D01*
G03X809942Y1920602I299J-266D01*
G02X809915Y1917098I-1937J-1737D01*
G03X809906Y1916565I294J-272D01*
G02X809659Y1912915I-1970J-1700D01*
G37*
G36*
G01X268722Y1918100D02*
G03Y1917500I264J-300D01*
G02X265276I-1723J-1950D01*
G03Y1918100I-264J300D01*
G02Y1922000I1723J1950D01*
G03Y1922600I-264J300D01*
G02Y1926500I1723J1950D01*
G03Y1927100I-264J300D01*
G02Y1931000I1723J1950D01*
G03Y1931600I-264J300D01*
G02X268722I1723J1950D01*
G03Y1931000I264J-300D01*
G02Y1927100I-1723J-1950D01*
G03Y1926500I264J-300D01*
G02Y1922600I-1723J-1950D01*
G03Y1922000I264J-300D01*
G02Y1918100I-1723J-1950D01*
G37*
G36*
G01X282972Y1930963D02*
G03X283474Y1931144I150J371D01*
G02X284894Y1927829I2025J-1094D01*
G03X284418Y1927590I-104J-386D01*
G02X283439Y1926383I-2418J961D01*
G03Y1925717I222J-333D01*
G02Y1921383I-1440J-2167D01*
G03Y1920717I222J-333D01*
G02X280559I-1440J-2167D01*
G03Y1921383I-222J333D01*
G02Y1925717I1440J2167D01*
G03Y1926383I-222J333D01*
G02X282972Y1930963I1441J2167D01*
G37*
G36*
G01X24662Y1923661D02*
G03X25215Y1923647I284J282D01*
G02X25133Y1920322I1550J-1702D01*
G03X24580Y1920336I-284J-282D01*
G02X24662Y1923661I-1550J1702D01*
G37*
G36*
G01X300765Y1930610D02*
G03X300233I-266J-299D01*
G02X296360Y1931068I-1734J1940D01*
G03X295761Y1931135I-329J-228D01*
G02X296138Y1934532I-1762J1915D01*
G03X296737Y1934465I329J228D01*
G02X300233Y1934490I1762J-1915D01*
G03X300765I266J299D01*
G02X304449Y1934273I1734J-1940D01*
G03X305049I300J264D01*
G02Y1930827I1950J-1723D01*
G03X304449I-300J-264D01*
G02X300765Y1930610I-1950J1723D01*
G37*
G36*
G01X773144Y1938440D02*
G03Y1938160I143J-140D01*
G02X769854I-1645J-1610D01*
G03Y1938440I-143J140D01*
G02X773144I1645J1610D01*
G37*
G36*
G01X100721Y1938595D02*
G03X100188Y1938589I-263J-301D01*
G02X96788Y1942526I-1755J1921D01*
G03X96863Y1943064I-253J310D01*
G02X100936Y1946287I2136J1486D01*
G03X101527Y1946282I298J267D01*
G02X104850Y1942328I1906J-1772D01*
G03X104717Y1941801I218J-335D01*
G02X100721Y1938595I-2284J-1246D01*
G37*
G36*
G01X344371Y1945560D02*
G03X344315Y1944968I238J-321D01*
G02X341249Y1945258I-1694J-1559D01*
G03X341305Y1945850I-238J321D01*
G02X344371Y1945560I1694J1559D01*
G37*
G36*
G01X330171Y1946554D02*
G03X330210Y1946823I-126J156D01*
G02X333554Y1946346I1893J1310D01*
G03X333515Y1946077I126J-156D01*
G02X330171Y1946554I-1893J-1310D01*
G37*
G36*
G01X287286Y1946233D02*
G03X286736Y1946181I-248J-314D01*
G02X286422Y1949500I-1737J1510D01*
G03X286972Y1949552I248J314D01*
G02X287286Y1946233I1737J-1510D01*
G37*
G36*
G01X292237Y1960135D02*
G03X291638Y1960068I-270J-295D01*
G02X288059Y1963717I-2139J1482D01*
G03Y1964383I-222J333D01*
G02X287776Y1968500I1440J2167D01*
G03Y1969100I-264J300D01*
G02X291449Y1972773I1723J1950D01*
G03X292049I300J264D01*
G02X295722Y1969100I1950J-1723D01*
G03Y1968500I264J-300D01*
G02Y1964600I-1723J-1950D01*
G03Y1964000I264J-300D01*
G02X292237Y1960135I-1723J-1950D01*
G37*
G36*
G01X785537Y1969763D02*
G03Y1969163I264J-300D01*
G02X782091I-1723J-1950D01*
G03Y1969763I-264J300D01*
G02X781964Y1973542I1723J1950D01*
G03X781991Y1974075I-285J282D01*
G02X785866Y1973879I2025J1633D01*
G03X785839Y1973346I285J-282D01*
G02X785537Y1969763I-2025J-1634D01*
G37*
G36*
G01X773216Y1973521D02*
G03X773082Y1972988I215J-337D01*
G02X769412Y1973905I-2268J-1275D01*
G03X769546Y1974438I-215J337D01*
G02X773554Y1977647I2268J1274D01*
G03X774087Y1977645I268J298D01*
G02X774074Y1973765I1727J-1946D01*
G03X773541Y1973767I-268J-298D01*
G02X773216Y1973521I-1728J1945D01*
G37*
G36*
G01X151300Y1052002D02*
X179281D01*
X223381Y1096102D01*
X226800D01*
G02Y1090698I0J-2702D01*
G01X225619D01*
X181519Y1046598D01*
X151300D01*
G02Y1052002I0J2702D01*
G37*
G36*
G01X151393Y538206D02*
G03X151253Y537973I56J-192D01*
G02X147320Y539073I-2253J-473D01*
G01X147374Y539131D01*
Y540586D01*
G03X146728Y540901I-400J0D01*
G01X95377Y489551D01*
G03X95533Y488938I315J-246D01*
G02X95945Y488713I-1036J-2387D01*
G03X96544Y488913I222J333D01*
G02X97553Y485887I2455J-863D01*
G03X96954Y485687I-222J-333D01*
G02X95413Y484114I-2455J863D01*
G03X95279Y483447I140J-375D01*
G02X95319Y483409I-1772J-1905D01*
G03X95879I280J286D01*
G02X99422Y479600I1820J-1859D01*
G03Y479000I264J-300D01*
G02X95879Y475191I-1723J-1950D01*
G03X95319I-280J-286D01*
G02X91776Y479000I-1820J1859D01*
G03Y479600I-264J300D01*
G02X92585Y483986I1723J1950D01*
G03X92719Y484653I-140J375D01*
G02X92111Y485516I1779J1899D01*
G03X91498Y485672I-367J-159D01*
G01X70937Y465111D01*
G02X64582Y462478I-6356J6355D01*
G01X30468D01*
G02X28532Y461594I-2569J3064D01*
G02X28083Y460990I-2047J1053D01*
G03X28129Y460376I278J-288D01*
G02X28539Y456990I-1330J-1879D01*
G03X28554Y456450I302J-262D01*
G02X25159Y456357I-1655J-1600D01*
G03X25144Y456897I-302J262D01*
G02X25202Y460155I1655J1600D01*
G03X25156Y460769I-278J288D01*
G02X24776Y464189I1330J1879D01*
G03X24777Y464722I-298J267D01*
G02X28762Y466670I1722J1528D01*
G03X29267Y466359I393J73D01*
G02X30154Y466485I889J-3072D01*
G01X64580Y466484D01*
G03X68104Y467944I0J4984D01*
G01X77824Y477664D01*
G03X77463Y478339I-283J283D01*
G02X76353Y478229I-1111J5558D01*
G01X76352D01*
Y478230D01*
X31040D01*
G03X30769Y478117I1J-385D01*
G02X30375Y477783I-2196J2191D01*
G02X28129Y477007I-2438J3419D01*
G02X24713Y480073I-1829J1398D01*
G03X24730Y480344I-138J145D01*
G02X28784Y482188I1785J1454D01*
G03X29333Y481887I394J68D01*
G02X31039Y482232I1706J-4043D01*
G01X76352D01*
G03X77529Y482720I-1J1665D01*
G01X113688Y518880D01*
X113689D01*
X113929Y519119D01*
G03X114450Y520376I-1257J1257D01*
G01Y807000D01*
X114449D01*
G02X115742Y810122I4415J0D01*
G01X117878Y812258D01*
G03X120698Y819233I-7212J6973D01*
G02Y819283I1401J25D01*
G01Y1036164D01*
G02X123433Y1042766I9338J-1D01*
G01X127108Y1046441D01*
G03X127398Y1047140I-699J700D01*
G01Y1047752D01*
X126699Y1048450D01*
X124677D01*
X124650Y1048442D01*
G02X122067Y1051901I-651J2208D01*
G01X122099Y1051951D01*
Y1052749D01*
X122067Y1052799D01*
G02X125250Y1055982I1932J1251D01*
G01X125300Y1055950D01*
X126000D01*
Y1055500D01*
X127249D01*
X128612Y1054137D01*
X128649Y1054122D01*
G02X130033Y1053195I-1651J-3961D01*
G02X130070Y1053157I-986J-997D01*
G02X131401Y1049893I-3336J-3264D01*
G01X131400D01*
Y1047141D01*
G02X130855Y1044872I-4991J-1D01*
G01X130789Y1044742D01*
X130930Y1044601D01*
X126264Y1039935D01*
G03X124702Y1036163I3772J-3772D01*
G01Y819233D01*
G02X120591Y809309I-14035J0D01*
G01X118573Y807291D01*
G03X118452Y807000I291J-292D01*
G01Y520376D01*
X118453D01*
G02X118334Y519212I-5781J3D01*
G03X119009Y518849I392J-80D01*
G01X144478Y544318D01*
G03X145238Y546150I-1831J1833D01*
G01Y551197D01*
X145180Y551256D01*
G02X144698Y552429I1189J1174D01*
G01Y554291D01*
G02X145180Y555464I1671J-1D01*
G01X145238Y555523D01*
Y555997D01*
X145180Y556056D01*
G02X144698Y557229I1189J1174D01*
G01Y559091D01*
G02X145180Y560264I1671J-1D01*
G01X145238Y560323D01*
Y581323D01*
X145180Y581382D01*
G02X144698Y582555I1189J1174D01*
G01Y584417D01*
G02X145180Y585590I1671J-1D01*
G01X145238Y585649D01*
Y586123D01*
X145180Y586182D01*
G02X144698Y587355I1189J1174D01*
G01Y589217D01*
G02X145180Y590390I1671J-1D01*
G01X145238Y590449D01*
Y590923D01*
X145180Y590982D01*
G02X144698Y592155I1189J1174D01*
G01Y594017D01*
G02X145180Y595190I1671J-1D01*
G01X145238Y595249D01*
Y598952D01*
X145407D01*
X145447Y599098D01*
G02X146947Y601677I5627J-1547D01*
G01X155659Y610390D01*
G02X155695Y610425I995J-987D01*
G03X156398Y612172I-1817J1746D01*
G01Y636036D01*
G03X155808Y637459I-2013J-1D01*
G03X154385Y638048I-1423J-1423D01*
G01X151199D01*
G02X146870Y642378I1J4330D01*
G01Y643833D01*
G03X146139Y644058I-400J0D01*
G02X142591Y646964I-1901J1297D01*
G03Y647523I-286J280D01*
G02X144308Y651432I1647J1608D01*
G03X144603Y652115I13J400D01*
G01X137809Y658909D01*
G03X136627Y659399I-1182J-1182D01*
G01X129849D01*
G03X129391Y659209I0J-648D01*
G01X128939Y658757D01*
G03X128502Y657700I1058J-1056D01*
G01X128501Y654290D01*
G03X128791Y653591I989J1D01*
G01X130201Y652181D01*
G02X131602Y648800I-3381J-3382D01*
G01Y647497D01*
G03X131672Y646886I2695J-1D01*
G02X129397Y643466I-272J-2286D01*
G03X129125Y643542I-174J-98D01*
G02X127447Y647785I-1126J2008D01*
G01X127590Y647820D01*
G03X127596Y647967I-2008J156D01*
G01Y648799D01*
G03X127368Y649348I-776J0D01*
G01X125958Y650758D01*
G02X124496Y654290I3532J3531D01*
G01Y657699D01*
G02X126106Y661590I5501J2D01*
G01X127551Y663035D01*
X127705Y662881D01*
G02X129850Y663405I2145J-4129D01*
G01X136626D01*
G02X139523Y662610I0J-5677D01*
G01X139649Y662735D01*
X149785Y652599D01*
X149685Y652499D01*
G02X150876Y648562I-5923J-3941D01*
G01Y642378D01*
G03X151199Y642054I324J0D01*
G01X154386D01*
G02X158641Y640292I0J-6019D01*
G02X160404Y636037I-4256J-4256D01*
G01Y612171D01*
G02X158492Y607557I-6526J1D01*
G01X149780Y598844D01*
G03X149244Y597550I1294J-1294D01*
G01Y547509D01*
G03X149768Y547182I397J52D01*
G02X152596Y544049I732J-2182D01*
G03X152788Y543523I364J-165D01*
G01X831289Y219736D01*
X833305Y217720D01*
X833397Y217727D01*
G02X831676Y214132I179J-2295D01*
G03X831134Y214246I-330J-225D01*
G02X827694Y215603I-1217J1954D01*
G01X827670Y215692D01*
X151768Y538349D01*
X151684Y538312D01*
G02X151393Y538206I-932J2105D01*
G37*
G36*
G01X59199Y527531D02*
X60339Y526390D01*
G03X73469Y520951I13130J13130D01*
G01Y520952D01*
X95117D01*
G02X98040Y519741I-1J-4135D01*
G02X98076Y519703I-999J-983D01*
G02X99402Y516456I-3320J-3250D01*
G01Y515652D01*
X99545Y515610D01*
G02X97336Y511711I-645J-2210D01*
G03X97064I-136J-147D01*
G02X95377Y515699I-1564J1689D01*
G03X95390Y515900I-1474J196D01*
G01Y516455D01*
G03X95204Y516904I-635J0D01*
G03X95117Y516941I-88J-87D01*
G01Y516940D01*
X90074D01*
G02X88773Y516340I-1301J1111D01*
G01X86973D01*
G02X85672Y516940I0J1711D01*
G01X73468D01*
G02X57502Y523554I1J22580D01*
G01X56362Y524694D01*
G03X54500Y525466I-1863J-1863D01*
G01X52332D01*
G02X51059Y524890I-1274J1121D01*
G01X49233D01*
G02X47960Y525466I1J1697D01*
G01X47532D01*
G02X46259Y524890I-1274J1121D01*
G01X44433D01*
G02X43160Y525466I1J1697D01*
G01X42732D01*
G02X41459Y524890I-1274J1121D01*
G01X39633D01*
G02X38360Y525466I1J1697D01*
G01X29562Y525465D01*
G02X29033Y525486I5J6798D01*
G03X28877Y525319I42J-196D01*
G02X24903Y527205I-2278J329D01*
G03Y527745I-295J270D01*
G02X28887Y529559I1696J1557D01*
G03X29561Y529476I675J2704D01*
G01X55900D01*
Y529329D01*
X56054Y529292D01*
G02X59199Y527531I-1553J-6462D01*
G37*
G36*
G01X27246Y1370537D02*
G03X27254Y1370004I302J-262D01*
G02X23819Y1369955I-1696J-1557D01*
G03X23811Y1370488I-302J262D01*
G02X27246Y1370537I1696J1557D01*
G37*
G36*
G01X31281Y1391431D02*
G02X30118Y1388755I1052J-2048D01*
G03X29551Y1389002I-385J-109D01*
G02X28449Y1393351I-1052J2048D01*
G03X28745Y1394010I-9J400D01*
G02X30550Y1393199I1754J1490D01*
G03X30254Y1392540I9J-400D01*
G02X30714Y1391678I-1755J-1490D01*
G03X31281Y1391431I385J109D01*
G37*
G36*
G01X30479Y1659398D02*
G03X30207Y1659391I-132J-150D01*
G02X30120Y1662768I-1607J1648D01*
G03X30392Y1662775I132J150D01*
G02X30479Y1659398I1607J-1648D01*
G37*
G36*
G01X30735Y1611835D02*
G03X30463I-136J-147D01*
G02Y1615213I-1564J1689D01*
G03X30735I136J147D01*
G02Y1611835I1564J-1689D01*
G37*
G36*
G01X53981Y769411D02*
G03X53914Y768812I228J-329D01*
G02X50026Y765353I-1915J-1762D01*
G03X49493Y765420I-303J-261D01*
G02X46059Y769284I-1494J2130D01*
G03Y769816I-299J266D01*
G02X49949Y773273I1940J1734D01*
G03X50549I300J264D01*
G02X53981Y769411I1950J-1723D01*
G37*
G36*
G01X90147Y843700D02*
X90743D01*
X90784Y843602D01*
G02X90147Y843700I-283J283D01*
G37*
G36*
G01X113265Y1116110D02*
G03X112733I-266J-299D01*
G02X109059Y1119784I-1734J1940D01*
G03Y1120316I-299J266D01*
G02Y1123784I1940J1734D01*
G03Y1124316I-299J266D01*
G02X109276Y1128000I1940J1734D01*
G03Y1128600I-264J300D01*
G02X112930Y1132294I1723J1950D01*
G03X113490Y1132261I297J268D01*
G02X116947Y1128371I1710J-1961D01*
G03X116920Y1127805I268J-296D01*
G02X116939Y1124316I-1921J-1755D01*
G03Y1123784I299J-266D01*
G02Y1120316I-1940J-1734D01*
G03Y1119784I299J-266D01*
G02X113265Y1116110I-1940J-1734D01*
G37*
G36*
G01X107873Y1100042D02*
G03X107320Y1099874I-196J-349D01*
G02X106868Y1099240I-2321J1176D01*
G03X106869Y1098682I287J-278D01*
G02X103421Y1094802I-1863J-1816D01*
G03X102888Y1094760I-243J-317D01*
G02X99276Y1098500I-1889J1790D01*
G03Y1099100I-264J300D01*
G02X102733Y1102990I1723J1950D01*
G03X103265I266J299D01*
G02X106494Y1103180I1734J-1940D01*
G03X107060Y1103291I230J327D01*
G02X107873Y1100042I1939J-1241D01*
G37*
G36*
G01X139188Y1079637D02*
G03Y1079101I297J-268D01*
G02X135770Y1079097I-1707J-1544D01*
G03Y1079633I-297J268D01*
G02X139188Y1079637I1707J1544D01*
G37*
G36*
G01X126119Y1079620D02*
G03Y1079080I295J-270D01*
G02X122727I-1696J-1557D01*
G03Y1079620I-295J270D01*
G02X126119I1696J1557D01*
G37*
G36*
G01X87859Y939073D02*
G03X87891Y938803I162J-118D01*
G02X84539Y938406I-1492J-1753D01*
G03X84507Y938676I-162J118D01*
G02X87859Y939073I1492J1753D01*
G37*
G36*
G01X96166Y880460D02*
G03X95634I-266J-299D01*
G02X92216Y884383I-1734J1940D01*
G03X92188Y885015I-259J305D01*
G02X92114Y889209I1502J2124D01*
G03X92088Y889864I-242J318D01*
G02X94993Y894180I1411J2186D01*
G03X95526Y894247I230J328D01*
G02X98920Y890370I1972J-1697D01*
G03X98947Y889684I218J-335D01*
G02X99223Y885291I-1247J-2284D01*
G03X99250Y884624I234J-325D01*
G02X96166Y880460I-1350J-2224D01*
G37*
G36*
G01X99248Y854666D02*
G03X99221Y853980I191J-351D01*
G02X95942Y849978I-1422J-2180D01*
G03X95411Y850013I-285J-280D01*
G02X92351Y854219I-1603J2050D01*
G03X92376Y854862I-225J331D01*
G02X92410Y858954I1625J2033D01*
G03X92316Y859641I-245J316D01*
G02X95119Y863909I983J2409D01*
G03X95679I280J286D01*
G02X99066Y859973I1820J-1859D01*
G03X99133Y859293I241J-320D01*
G02X99248Y854666I-1132J-2343D01*
G37*
G36*
G01X107322Y1078271D02*
G02X105075Y1077663I-605J-2221D01*
G03X104895Y1078329I-285J280D01*
G02X107142Y1078937I605J2221D01*
G03X107322Y1078271I285J-280D01*
G37*
G36*
G01X114408Y1359729D02*
G03X114363Y1359461I122J-158D01*
G02X111031Y1360017I-1923J-1265D01*
G03X111076Y1360285I-122J158D01*
G02X114408Y1359729I1923J1265D01*
G37*
G36*
G01X110875Y1335482D02*
G03Y1334923I286J-280D01*
G02X107581I-1647J-1608D01*
G03Y1335482I-286J279D01*
G02X110875I1647J1608D01*
G37*
G36*
G01X98507Y1375860D02*
G03X98541Y1375229I262J-302D01*
G02X95722Y1375077I-1312J-1892D01*
G03X95688Y1375708I-262J302D01*
G02X98507Y1375860I1312J1892D01*
G37*
G36*
G01X88537Y1345027D02*
G03Y1344468I286J-280D01*
G02X85243I-1647J-1608D01*
G03Y1345027I-286J280D01*
G02X88537I1647J1608D01*
G37*
G54D29*
X68898Y17047D03*
Y190275D03*
Y422559D03*
Y595787D03*
X167323Y353031D03*
Y585315D03*
Y1164055D03*
Y1396339D03*
Y1569567D03*
Y1801851D03*
Y1975079D03*
X895669Y179803D03*
Y353031D03*
Y585315D03*
Y758543D03*
Y990827D03*
Y1164055D03*
Y1396339D03*
Y1569567D03*
Y1801851D03*
Y1975079D03*
G54D23*
X799385Y761436D03*
X904814Y1789113D03*
X903999Y574378D03*
X904999Y67550D03*
X904499Y74050D03*
X881499Y70550D03*
X883999Y39050D03*
X943499Y55050D03*
Y48050D03*
X929999Y32550D03*
X916499Y36050D03*
X909499Y21550D03*
X909999Y35550D03*
X902499Y35050D03*
X902999Y22050D03*
X917499Y21550D03*
X873499Y1356050D03*
X838499Y99550D03*
X837999Y91050D03*
X865499Y125550D03*
X875499D03*
X855499Y82050D03*
X867499D03*
X876999D03*
X839499Y119050D03*
X845999Y111050D03*
X838499Y107050D03*
X841499Y71550D03*
X840999Y62550D03*
X840499Y55050D03*
X839999Y46050D03*
X856499Y71050D03*
X866999Y70550D03*
X854499Y39550D03*
X865499D03*
X767999Y1923050D03*
X773999Y1923550D03*
X767159Y1792364D03*
X757500Y1522500D03*
X751499Y679148D03*
X717000Y1812384D03*
X633837Y1807384D03*
X544300Y1784638D03*
X563499Y1503550D03*
X334999Y1797050D03*
X326301Y1766030D03*
X266999Y1512550D03*
X260999Y1503550D03*
X305998Y352114D03*
X307999Y78550D03*
X226999Y1941050D03*
X180000Y1619600D03*
X192499Y57550D03*
X183499Y45550D03*
X225499Y46550D03*
X199999Y46050D03*
X208499Y45650D03*
X119499Y1972550D03*
X126999D03*
X132999D03*
X119999Y1978550D03*
X133499D03*
X127499D03*
X122600Y1565000D03*
X159186Y946117D03*
X161999Y768050D03*
X171300Y476700D03*
X164600D03*
X154100Y476500D03*
X149700Y471600D03*
X136349Y509050D03*
X145649Y509550D03*
X135140Y478930D03*
X135999Y472550D03*
X100500Y456700D03*
X155999Y181050D03*
X129999Y78050D03*
X127999Y99550D03*
X114800Y68500D03*
X116400Y56000D03*
X167499Y43550D03*
X141999Y65550D03*
X127499Y65050D03*
X156499Y66050D03*
X129100Y55900D03*
X58999Y1958050D03*
X66499Y1957050D03*
X73499D03*
X82499D03*
X92499Y1959050D03*
X47499Y1915050D03*
X73499Y1945550D03*
X47499Y1930550D03*
X62999Y1914550D03*
X83999Y1945050D03*
X62499Y1939550D03*
X81499Y1915550D03*
X62999Y1926050D03*
X94500Y456800D03*
X866499Y724550D03*
X864414Y1940050D03*
X67000Y1011500D03*
G54D22*
X867899Y321550D03*
X868799Y294750D03*
X249499Y1928050D03*
X213138Y1952703D03*
X214999Y1909550D03*
X93999Y1703050D03*
X101399Y1292550D03*
X101541Y1262607D03*
X961499Y93350D03*
X917499Y1796550D03*
X886439Y1717600D03*
X889800Y1711500D03*
X900999Y979050D03*
X900499Y962100D03*
X902999Y556050D03*
X916499Y172550D03*
X910999Y124550D03*
X926999Y122050D03*
X938499Y115550D03*
X907499Y131800D03*
X854814Y1883550D03*
X828500Y1877800D03*
X827700Y1487600D03*
X809960Y1478040D03*
X854327Y1477550D03*
X807000Y1072900D03*
X825700Y1083100D03*
X852333Y1077716D03*
X808660Y667540D03*
X852696Y671197D03*
X829800Y666650D03*
X809940Y264940D03*
X827500Y274500D03*
X842499Y280924D03*
X822100Y279500D03*
X854400Y264600D03*
X837999Y219550D03*
X802499Y1951550D03*
X782999Y1937050D03*
X794499Y1941050D03*
X792499Y1949050D03*
X758499Y1893550D03*
X800431Y1941193D03*
X733149Y1798634D03*
X732549Y1806634D03*
X733049Y1814134D03*
X757999Y1484050D03*
X757499Y1079550D03*
X769999Y733050D03*
X780499Y330050D03*
X707600Y1815600D03*
X385499Y1735050D03*
X348499Y1762050D03*
X353499Y1710450D03*
X402499Y1476850D03*
X350499Y715050D03*
Y597300D03*
X365499Y86550D03*
X394199Y45050D03*
X310499Y1957050D03*
X257499Y1911050D03*
X261999Y1516050D03*
X326500Y1550200D03*
X282500Y1135000D03*
X269500Y1135500D03*
X279939Y728610D03*
X301249Y346050D03*
X297499Y97550D03*
X282800Y87500D03*
X308999Y87050D03*
X249600Y1896800D03*
X223436Y1890465D03*
X201499Y1781050D03*
X224750Y1483950D03*
X194700Y1385700D03*
X179499Y1275550D03*
X247500Y1085500D03*
X254499Y697700D03*
X246800Y677100D03*
X220000Y516400D03*
X253871Y291410D03*
X225298Y281114D03*
X247800Y269700D03*
X237899Y107050D03*
X233749Y110800D03*
X223499Y108150D03*
X188999Y120800D03*
X186999Y99050D03*
X213499Y104650D03*
X230749Y76300D03*
X101399Y1784700D03*
X110099Y1759875D03*
X141999Y1764550D03*
X99999Y1753575D03*
X117499Y1706050D03*
X171999Y1662250D03*
X106999Y1454450D03*
X100699Y1471050D03*
X119399Y1298113D03*
X135850Y1322250D03*
X123970Y1221573D03*
X106162Y1205702D03*
X103999Y1216863D03*
X103686Y1223863D03*
X170250Y948500D03*
X152500Y960000D03*
X172000Y961000D03*
X108200Y963600D03*
X153499Y918550D03*
X110499Y834550D03*
X110500Y790200D03*
X138416Y553500D03*
X176799Y493850D03*
X172499Y491053D03*
X107499Y497050D03*
X135499Y517550D03*
X171722Y513827D03*
X163549Y517100D03*
X159600Y446399D03*
X176399Y94872D03*
X175499Y86572D03*
X25499Y1956050D03*
X32999Y1960555D03*
X43462Y1961160D03*
X50499Y1961550D03*
X31799Y1979050D03*
X57999Y1891050D03*
X48499Y1897050D03*
X42499Y1902550D03*
X80999Y1836550D03*
X97999Y1843050D03*
X86649Y1817100D03*
X85599Y1797350D03*
X99199Y1761899D03*
X98599Y1491350D03*
X81251Y619251D03*
Y607249D03*
X25581Y567763D03*
X26199Y547176D03*
X42599Y567850D03*
X36499Y566350D03*
X65599Y514250D03*
X45800Y405200D03*
X97499Y90050D03*
X11703Y1951946D03*
X17499Y1961050D03*
X14999Y1936050D03*
X15099Y1944050D03*
X8499Y1937550D03*
X116999Y1288050D03*
X95499Y1665418D03*
X118499Y1694050D03*
X231999Y1914050D03*
X210999Y1942050D03*
X264499Y1964050D03*
X868299Y336150D03*
X865499Y288050D03*
X857099Y1917650D03*
X863699Y1906450D03*
X862800Y1712700D03*
X873800Y1733600D03*
X867523Y1542821D03*
X867199Y1535150D03*
X863699Y1501250D03*
X864499Y1128750D03*
X804899Y1556950D03*
X834799Y1946950D03*
X802099Y1961950D03*
X803199Y1151850D03*
X343499Y31650D03*
X25000Y1357742D03*
X25521Y1563350D03*
X30500Y1697500D03*
X94999Y901550D03*
X104600Y980500D03*
X107300Y986000D03*
X107400Y992900D03*
X125900Y1091282D03*
X105999Y1085800D03*
X101499Y1072550D03*
X116700Y1063500D03*
X105600Y1069500D03*
X112699Y1058974D03*
X120749Y1093990D03*
X132499Y1094550D03*
X123999Y1102550D03*
G54D27*
X886417Y1963268D03*
Y1813662D03*
Y1557756D03*
Y1408150D03*
Y1152244D03*
Y1002638D03*
Y746732D03*
Y597126D03*
Y341220D03*
Y191614D03*
X158071Y1963268D03*
Y1813662D03*
Y1557756D03*
Y1408150D03*
Y1152244D03*
Y1002638D03*
Y746732D03*
Y341220D03*
Y191614D03*
X78150Y839882D03*
Y583976D03*
Y434370D03*
Y178464D03*
Y28858D03*
G54D28*
X9843Y1859468D03*
Y353144D03*
Y1746869D03*
G54D25*
X994098Y1068880D03*
Y673210D03*
Y149588D03*
X271657Y1889746D03*
Y1484234D03*
Y1078722D03*
Y673210D03*
Y267699D03*
X17720Y1903132D03*
X29531Y309549D03*
G54D26*
X1019291Y1416024D03*
G54D24*
X994093Y1889751D03*
%LPD*%
G75*
G36*
G01X279499Y21550D02*
X306999Y49050D01*
X312499D01*
X315999Y45550D01*
Y41550D01*
X284499Y10050D01*
X149499D01*
X139491Y20058D01*
X139477Y20112D01*
G03X123132Y24855I-9556J-2396D01*
G01X123074Y24800D01*
X95749D01*
X79499Y41050D01*
Y45550D01*
X80499Y46550D01*
X84300D01*
X84501Y46348D01*
X93200D01*
X104249Y35300D01*
X141749D01*
X155499Y21550D01*
X279499D01*
G37*
G36*
G01X156499Y23050D02*
X142999Y36550D01*
X105499D01*
X94499Y47550D01*
X84999D01*
X82999Y49550D01*
Y55050D01*
X84499Y56550D01*
X92858D01*
X92903Y56526D01*
G03X95095I1096J2024D01*
G01X95140Y56550D01*
X100999D01*
X112999Y44550D01*
X146999D01*
X160499Y31050D01*
X272999D01*
X286499Y44550D01*
X289499D01*
X292499Y41550D01*
Y36550D01*
X278999Y23050D01*
X156499D01*
G37*
G36*
G01X204999Y881550D02*
X157999Y928550D01*
X151999D01*
X148999Y931550D01*
Y936550D01*
X150499Y938050D01*
X163699D01*
X163724Y938024D01*
X166226D01*
X168834Y935416D01*
X168820Y935318D01*
G03X169931Y933017I2280J-318D01*
G02X170003Y932745I-101J-172D01*
G03X173663Y930009I1997J-1144D01*
G02X174235Y930015I289J-277D01*
G01X209455Y894795D01*
X209450Y894707D01*
G03X211857Y892300I2300J-107D01*
G01X211945Y892305D01*
X214200Y890050D01*
X224499D01*
X225999Y888550D01*
Y884050D01*
X223499Y881550D01*
X204999D01*
G37*
%LPC*%
G75*
G54D22*
X200539Y890300D03*
X200799Y896600D03*
%LPD*%
G75*
G54D10*
X-38436Y23633D03*
X-36811Y1104775D03*
X-35919Y1969497D03*
X9843Y353144D03*
Y717711D03*
Y762617D03*
Y875216D03*
Y1337396D03*
Y1701963D03*
Y1746869D03*
Y1859468D03*
X78150Y28858D03*
Y178464D03*
Y434370D03*
Y583976D03*
Y839882D03*
Y989488D03*
Y1245394D03*
Y1395000D03*
Y1650906D03*
Y1800512D03*
X158071Y191614D03*
Y341220D03*
Y597126D03*
Y746732D03*
Y1002638D03*
Y1152244D03*
Y1408150D03*
Y1557756D03*
Y1813662D03*
Y1963268D03*
X886417Y191614D03*
Y341220D03*
Y597126D03*
Y746732D03*
Y1002638D03*
Y1152244D03*
Y1408150D03*
Y1557756D03*
Y1813662D03*
Y1963268D03*
X1019291Y1416024D03*
Y1694212D03*
X1072493Y21507D03*
X1075940Y1769358D03*
G54D20*
G01X-53190Y-209897D02*
Y-192397D01*
G01X-44894D02*
X-53190Y-203189D01*
G01X-43584Y-209897D02*
X-49479Y-198231D01*
G01X-35909Y-209897D02*
Y-192397D01*
X-25865Y-209897D01*
Y-192397D01*
G01X-13387Y-209897D02*
X-15134Y-209605D01*
X-16662Y-208439D01*
X-17972Y-206689D01*
X-18846Y-204647D01*
X-19282Y-202314D01*
Y-199980D01*
X-18846Y-197647D01*
X-17972Y-195605D01*
X-16662Y-193856D01*
X-15134Y-192689D01*
X-13387Y-192397D01*
X-11641Y-192689D01*
X-10112Y-193856D01*
X-8802Y-195605D01*
X-7928Y-197647D01*
X-7492Y-199980D01*
Y-202314D01*
X-7928Y-204647D01*
X-8802Y-206689D01*
X-10112Y-208439D01*
X-11641Y-209605D01*
X-13387Y-209897D01*
G01X-472D02*
X8698Y-192397D01*
G01X-472D02*
X8698Y-209897D01*
G01X34310D02*
Y-192397D01*
X38676D01*
X40423Y-193272D01*
X41733Y-194439D01*
X42825Y-196188D01*
X43698Y-198231D01*
X43916Y-201147D01*
X43698Y-204064D01*
X42825Y-206106D01*
X41733Y-207856D01*
X40423Y-209022D01*
X38676Y-209897D01*
X34310D01*
G01X52246D02*
Y-192397D01*
X57705D01*
X59451Y-193272D01*
X60543Y-194439D01*
X60980Y-196772D01*
X60543Y-199106D01*
X59233Y-200564D01*
X57705Y-201439D01*
X52246D01*
G01X57705D02*
X60980Y-209897D01*
G01X71493Y-192397D02*
X76733D01*
G01X74113D02*
Y-209897D01*
G01X71493D02*
X76733D01*
G01X86154Y-192397D02*
X91613Y-209897D01*
X97072Y-192397D01*
G01X113480Y-209897D02*
X104746D01*
Y-192397D01*
X113480D01*
G01X109986Y-200855D02*
X104746D01*
G01X139746Y-209897D02*
Y-192397D01*
X144986D01*
X146733Y-193272D01*
X148043Y-195314D01*
X148480Y-197647D01*
X148043Y-199980D01*
X146951Y-201730D01*
X144986Y-202606D01*
X139746D01*
G01X157246Y-192397D02*
Y-209897D01*
X165980D01*
G01X173654D02*
X179113Y-192397D01*
X184572Y-209897D01*
G01X182606Y-203772D02*
X175619D01*
G01X191591Y-209897D02*
Y-192397D01*
X201635Y-209897D01*
Y-192397D01*
G01X218480Y-209897D02*
X209746D01*
Y-192397D01*
X218480D01*
G01X214986Y-200855D02*
X209746D01*
G01X250859Y-200564D02*
X251733Y-199689D01*
X252388Y-198231D01*
X252825Y-196188D01*
X252388Y-194439D01*
X251515Y-193272D01*
X249986Y-192397D01*
X244091D01*
Y-209897D01*
X251296D01*
X252825Y-208731D01*
X253698Y-206980D01*
X254135Y-204939D01*
X253698Y-202897D01*
X252388Y-201147D01*
X250859Y-200564D01*
X244091D01*
G01X266613Y-209897D02*
X264866Y-209605D01*
X263338Y-208439D01*
X262028Y-206689D01*
X261154Y-204647D01*
X260718Y-202314D01*
Y-199980D01*
X261154Y-197647D01*
X262028Y-195605D01*
X263338Y-193856D01*
X264866Y-192689D01*
X266613Y-192397D01*
X268359Y-192689D01*
X269888Y-193856D01*
X271198Y-195605D01*
X272072Y-197647D01*
X272508Y-199980D01*
Y-202314D01*
X272072Y-204647D01*
X271198Y-206689D01*
X269888Y-208439D01*
X268359Y-209605D01*
X266613Y-209897D01*
G01X278654D02*
X284113Y-192397D01*
X289572Y-209897D01*
G01X287606Y-203772D02*
X280619D01*
G01X297246Y-209897D02*
Y-192397D01*
X302705D01*
X304451Y-193272D01*
X305543Y-194439D01*
X305980Y-196772D01*
X305543Y-199106D01*
X304233Y-200564D01*
X302705Y-201439D01*
X297246D01*
G01X302705D02*
X305980Y-209897D01*
G01X314310D02*
Y-192397D01*
X318676D01*
X320423Y-193272D01*
X321733Y-194439D01*
X322825Y-196188D01*
X323698Y-198231D01*
X323916Y-201147D01*
X323698Y-204064D01*
X322825Y-206106D01*
X321733Y-207856D01*
X320423Y-209022D01*
X318676Y-209897D01*
X314310D01*
G01X94686Y-164897D02*
Y-147397D01*
X100363Y-161980D01*
X106040Y-147397D01*
Y-164897D01*
G01X117863D02*
X116553Y-164605D01*
X115243Y-163439D01*
X114369Y-161397D01*
X113933Y-159064D01*
X114369Y-156730D01*
X115243Y-154689D01*
X116553Y-153522D01*
X117863Y-153231D01*
X119173Y-153522D01*
X120483Y-154689D01*
X121356Y-156730D01*
X121575Y-159064D01*
X121356Y-161397D01*
X120483Y-163439D01*
X119173Y-164605D01*
X117863Y-164897D01*
G01X139293Y-147397D02*
Y-164897D01*
G01Y-162273D02*
X138420Y-163731D01*
X137109Y-164605D01*
X135581Y-164897D01*
X133835Y-164314D01*
X132525Y-162856D01*
X131651Y-161106D01*
X131433Y-159064D01*
X131651Y-157022D01*
X132525Y-155272D01*
X133835Y-153814D01*
X135581Y-153231D01*
X137109Y-153522D01*
X138201Y-154106D01*
X139293Y-155272D01*
G01X149588Y-157022D02*
X156575D01*
X155920Y-154980D01*
X154828Y-153814D01*
X153300Y-153231D01*
X151771Y-153522D01*
X150461Y-154397D01*
X149588Y-156439D01*
X149151Y-158189D01*
Y-159939D01*
X149588Y-161689D01*
X150680Y-163439D01*
X151990Y-164605D01*
X153518Y-164897D01*
X155046Y-164314D01*
X156575Y-162564D01*
G01X170363Y-164897D02*
Y-147397D01*
G01X376163Y-209897D02*
Y-192397D01*
X373543Y-195897D01*
G01Y-209897D02*
X378783D01*
G01X389515Y-195314D02*
X390825Y-193564D01*
X392353Y-192689D01*
X394100Y-192397D01*
X396283Y-192980D01*
X397811Y-194439D01*
X398248Y-196188D01*
X398030Y-197939D01*
X397156Y-199397D01*
X392790Y-202314D01*
X390825Y-204355D01*
X389515Y-207273D01*
X389078Y-209897D01*
X398248D01*
G01X413783D02*
Y-192397D01*
X405704Y-204939D01*
X416622D01*
G01X423860Y-206397D02*
X425169Y-208439D01*
X426916Y-209605D01*
X428881Y-209897D01*
X430628Y-209605D01*
X432375Y-208147D01*
X433466Y-206397D01*
X433685Y-204647D01*
X433248Y-202606D01*
X431720Y-201147D01*
X430191Y-200564D01*
X428226D01*
G01X430191D02*
X431501Y-199689D01*
X432593Y-198231D01*
X433030Y-196481D01*
X432593Y-194730D01*
X431501Y-193272D01*
X429536Y-192397D01*
X427571Y-192689D01*
X425606Y-193856D01*
G01X442015Y-195314D02*
X443325Y-193564D01*
X444853Y-192689D01*
X446600Y-192397D01*
X448783Y-192980D01*
X450311Y-194439D01*
X450748Y-196188D01*
X450530Y-197939D01*
X449656Y-199397D01*
X445290Y-202314D01*
X443325Y-204355D01*
X442015Y-207273D01*
X441578Y-209897D01*
X450748D01*
G01X363046Y-164897D02*
Y-147397D01*
X368286D01*
X370033Y-148272D01*
X371343Y-150314D01*
X371780Y-152647D01*
X371343Y-154980D01*
X370251Y-156730D01*
X368286Y-157606D01*
X363046D01*
G01X389716Y-148856D02*
X388406Y-147980D01*
X386878Y-147397D01*
X385131D01*
X383166Y-148272D01*
X381638Y-149730D01*
X380546Y-151481D01*
X379673Y-154397D01*
X379454Y-157022D01*
X379891Y-159647D01*
X380546Y-161397D01*
X381856Y-163147D01*
X383385Y-164314D01*
X384913Y-164897D01*
X386441D01*
X387970Y-164314D01*
X389280Y-163439D01*
X390372Y-162273D01*
G01X404159Y-155564D02*
X405033Y-154689D01*
X405688Y-153231D01*
X406125Y-151188D01*
X405688Y-149439D01*
X404815Y-148272D01*
X403286Y-147397D01*
X397391D01*
Y-164897D01*
X404596D01*
X406125Y-163731D01*
X406998Y-161980D01*
X407435Y-159939D01*
X406998Y-157897D01*
X405688Y-156147D01*
X404159Y-155564D01*
X397391D01*
G01X413363Y-170730D02*
X426463D01*
G01X432391Y-164897D02*
Y-147397D01*
X442435Y-164897D01*
Y-147397D01*
G01X454913Y-164897D02*
X453166Y-164605D01*
X451638Y-163439D01*
X450328Y-161689D01*
X449454Y-159647D01*
X449018Y-157314D01*
Y-154980D01*
X449454Y-152647D01*
X450328Y-150605D01*
X451638Y-148856D01*
X453166Y-147689D01*
X454913Y-147397D01*
X456659Y-147689D01*
X458188Y-148856D01*
X459498Y-150605D01*
X460372Y-152647D01*
X460808Y-154980D01*
Y-157314D01*
X460372Y-159647D01*
X459498Y-161689D01*
X458188Y-163439D01*
X456659Y-164605D01*
X454913Y-164897D01*
G01X505754Y-147397D02*
X511213Y-164897D01*
X516672Y-147397D01*
G01X533080Y-164897D02*
X524346D01*
Y-147397D01*
X533080D01*
G01X529586Y-155855D02*
X524346D01*
G01X541846Y-164897D02*
Y-147397D01*
X547305D01*
X549051Y-148272D01*
X550143Y-149439D01*
X550580Y-151772D01*
X550143Y-154106D01*
X548833Y-155564D01*
X547305Y-156439D01*
X541846D01*
G01X547305D02*
X550580Y-164897D01*
G01X563713Y-165480D02*
X563276Y-165189D01*
Y-164605D01*
X563713Y-164314D01*
X564150Y-164605D01*
Y-165189D01*
X563713Y-165480D01*
G01X537463Y-209897D02*
Y-192397D01*
X534843Y-195897D01*
G01Y-209897D02*
X540083D01*
G01X630546Y-147397D02*
Y-164897D01*
X639280D01*
G01X656343D02*
Y-153231D01*
G01Y-155272D02*
X655470Y-154106D01*
X654159Y-153522D01*
X652631Y-153231D01*
X651103Y-153814D01*
X649793Y-154980D01*
X648919Y-156730D01*
X648483Y-159064D01*
X648919Y-161397D01*
X649793Y-163147D01*
X651103Y-164314D01*
X652631Y-164897D01*
X654159Y-164605D01*
X655470Y-163731D01*
X656343Y-162564D01*
G01X665328Y-170147D02*
X666638Y-170730D01*
X668385Y-170147D01*
X669476Y-168981D01*
X670350Y-167522D01*
X671659Y-162856D01*
X674498Y-153231D01*
G01X667511D02*
X671659Y-162856D01*
G01X684138Y-157022D02*
X691125D01*
X690470Y-154980D01*
X689378Y-153814D01*
X687850Y-153231D01*
X686321Y-153522D01*
X685011Y-154397D01*
X684138Y-156439D01*
X683701Y-158189D01*
Y-159939D01*
X684138Y-161689D01*
X685230Y-163439D01*
X686540Y-164605D01*
X688068Y-164897D01*
X689596Y-164314D01*
X691125Y-162564D01*
G01X701856Y-164897D02*
Y-153231D01*
G01Y-155564D02*
X702948Y-154397D01*
X704040Y-153522D01*
X705568Y-153231D01*
X706659Y-153522D01*
X707970Y-154397D01*
G01X719138Y-162856D02*
X720230Y-164022D01*
X721758Y-164897D01*
X723068D01*
X724378Y-164314D01*
X725251Y-163439D01*
X725688Y-162273D01*
X725470Y-160522D01*
X724596Y-159647D01*
X720666Y-157897D01*
X719793Y-155855D01*
X720230Y-154397D01*
X721103Y-153522D01*
X722413Y-153231D01*
X723723Y-153522D01*
X725033Y-154397D01*
G01X665546Y-192397D02*
Y-209897D01*
X674280D01*
G01X682610Y-206397D02*
X683919Y-208439D01*
X685666Y-209605D01*
X687631Y-209897D01*
X689378Y-209605D01*
X691125Y-208147D01*
X692216Y-206397D01*
X692435Y-204647D01*
X691998Y-202606D01*
X690470Y-201147D01*
X688941Y-200564D01*
X686976D01*
G01X688941D02*
X690251Y-199689D01*
X691343Y-198231D01*
X691780Y-196481D01*
X691343Y-194730D01*
X690251Y-193272D01*
X688286Y-192397D01*
X686321Y-192689D01*
X684356Y-193856D01*
G01X781410Y-164897D02*
Y-147397D01*
X785776D01*
X787523Y-148272D01*
X788833Y-149439D01*
X789925Y-151188D01*
X790798Y-153231D01*
X791016Y-156147D01*
X790798Y-159064D01*
X789925Y-161106D01*
X788833Y-162856D01*
X787523Y-164022D01*
X785776Y-164897D01*
X781410D01*
G01X800438Y-157022D02*
X807425D01*
X806770Y-154980D01*
X805678Y-153814D01*
X804150Y-153231D01*
X802621Y-153522D01*
X801311Y-154397D01*
X800438Y-156439D01*
X800001Y-158189D01*
Y-159939D01*
X800438Y-161689D01*
X801530Y-163439D01*
X802840Y-164605D01*
X804368Y-164897D01*
X805896Y-164314D01*
X807425Y-162564D01*
G01X817938Y-162856D02*
X819030Y-164022D01*
X820558Y-164897D01*
X821868D01*
X823178Y-164314D01*
X824051Y-163439D01*
X824488Y-162273D01*
X824270Y-160522D01*
X823396Y-159647D01*
X819466Y-157897D01*
X818593Y-155855D01*
X819030Y-154397D01*
X819903Y-153522D01*
X821213Y-153231D01*
X822523Y-153522D01*
X823833Y-154397D01*
G01X838713Y-153231D02*
Y-164897D01*
G01Y-148564D02*
X838276Y-148272D01*
Y-147689D01*
X838713Y-147397D01*
X839150Y-147689D01*
Y-148272D01*
X838713Y-148564D01*
G01X853156Y-169272D02*
X854685Y-170439D01*
X856431Y-170730D01*
X857959Y-170439D01*
X859270Y-168981D01*
X860143Y-166939D01*
Y-153231D01*
G01Y-155564D02*
X859270Y-154397D01*
X857959Y-153522D01*
X856431Y-153231D01*
X854685Y-153814D01*
X853593Y-154980D01*
X852719Y-157022D01*
X852283Y-159064D01*
X852501Y-160814D01*
X853375Y-162856D01*
X854685Y-164314D01*
X856431Y-164897D01*
X857741Y-164605D01*
X859270Y-163439D01*
X860143Y-162273D01*
G01X870001Y-164897D02*
Y-153231D01*
G01Y-156147D02*
X870875Y-154689D01*
X872185Y-153522D01*
X873931Y-153231D01*
X875459Y-153522D01*
X876770Y-154689D01*
X877425Y-156730D01*
Y-164897D01*
G01X887938Y-157022D02*
X894925D01*
X894270Y-154980D01*
X893178Y-153814D01*
X891650Y-153231D01*
X890121Y-153522D01*
X888811Y-154397D01*
X887938Y-156439D01*
X887501Y-158189D01*
Y-159939D01*
X887938Y-161689D01*
X889030Y-163439D01*
X890340Y-164605D01*
X891868Y-164897D01*
X893396Y-164314D01*
X894925Y-162564D01*
G01X905656Y-164897D02*
Y-153231D01*
G01Y-155564D02*
X906748Y-154397D01*
X907840Y-153522D01*
X909368Y-153231D01*
X910459Y-153522D01*
X911770Y-154397D01*
G01X825596Y-209897D02*
Y-192397D01*
X831055D01*
X832801Y-193272D01*
X833893Y-194439D01*
X834330Y-196772D01*
X833893Y-199106D01*
X832583Y-200564D01*
X831055Y-201439D01*
X825596D01*
G01X831055D02*
X834330Y-209897D01*
G01X847463D02*
X846153Y-209605D01*
X844843Y-208439D01*
X843969Y-206397D01*
X843533Y-204064D01*
X843969Y-201730D01*
X844843Y-199689D01*
X846153Y-198522D01*
X847463Y-198231D01*
X848773Y-198522D01*
X850083Y-199689D01*
X850956Y-201730D01*
X851175Y-204064D01*
X850956Y-206397D01*
X850083Y-208439D01*
X848773Y-209605D01*
X847463Y-209897D01*
G01X861033D02*
Y-192397D01*
G01Y-201147D02*
X862125Y-199397D01*
X863435Y-198522D01*
X864745Y-198231D01*
X866709Y-198814D01*
X868020Y-199980D01*
X868893Y-202022D01*
Y-204355D01*
X868456Y-206689D01*
X867583Y-208439D01*
X866055Y-209605D01*
X864745Y-209897D01*
X863435Y-209605D01*
X862125Y-208731D01*
X861033Y-207273D01*
G01X952413Y-209897D02*
Y-192397D01*
X949793Y-195897D01*
G01Y-209897D02*
X955033D01*
G01X969913Y-192397D02*
X968166Y-192980D01*
X966856Y-194439D01*
X965983Y-196188D01*
X965328Y-198522D01*
X965110Y-201147D01*
X965328Y-203772D01*
X965983Y-206106D01*
X966856Y-207856D01*
X968166Y-209314D01*
X969913Y-209897D01*
X971659Y-209314D01*
X972970Y-207856D01*
X973843Y-206106D01*
X974498Y-203772D01*
X974716Y-201147D01*
X974498Y-198522D01*
X973843Y-196188D01*
X972970Y-194439D01*
X971659Y-192980D01*
X969913Y-192397D01*
G01X983483Y-210480D02*
X991343Y-192397D01*
G01X1004913Y-209897D02*
Y-192397D01*
X1002293Y-195897D01*
G01Y-209897D02*
X1007533D01*
G01X1018265Y-202606D02*
X1019793Y-200564D01*
X1021103Y-199397D01*
X1022850Y-198814D01*
X1024378Y-199397D01*
X1025470Y-200564D01*
X1026343Y-202314D01*
X1026561Y-204355D01*
X1026343Y-206106D01*
X1025470Y-207856D01*
X1024159Y-209314D01*
X1022631Y-209897D01*
X1020885Y-209314D01*
X1019356Y-207564D01*
X1018483Y-204939D01*
X1018265Y-202022D01*
X1018701Y-198231D01*
X1019356Y-196188D01*
X1020448Y-194147D01*
X1021976Y-192689D01*
X1023505Y-192397D01*
X1025033Y-192980D01*
X1026125Y-194439D01*
G01X1035983Y-210480D02*
X1043843Y-192397D01*
G01X1053265Y-195314D02*
X1054575Y-193564D01*
X1056103Y-192689D01*
X1057850Y-192397D01*
X1060033Y-192980D01*
X1061561Y-194439D01*
X1061998Y-196188D01*
X1061780Y-197939D01*
X1060906Y-199397D01*
X1056540Y-202314D01*
X1054575Y-204355D01*
X1053265Y-207273D01*
X1052828Y-209897D01*
X1061998D01*
G01X1074913Y-192397D02*
X1073166Y-192980D01*
X1071856Y-194439D01*
X1070983Y-196188D01*
X1070328Y-198522D01*
X1070110Y-201147D01*
X1070328Y-203772D01*
X1070983Y-206106D01*
X1071856Y-207856D01*
X1073166Y-209314D01*
X1074913Y-209897D01*
X1076659Y-209314D01*
X1077970Y-207856D01*
X1078843Y-206106D01*
X1079498Y-203772D01*
X1079716Y-201147D01*
X1079498Y-198522D01*
X1078843Y-196188D01*
X1077970Y-194439D01*
X1076659Y-192980D01*
X1074913Y-192397D01*
G01X1092413Y-209897D02*
Y-192397D01*
X1089793Y-195897D01*
G01Y-209897D02*
X1095033D01*
G01X1105765Y-195314D02*
X1107075Y-193564D01*
X1108603Y-192689D01*
X1110350Y-192397D01*
X1112533Y-192980D01*
X1114061Y-194439D01*
X1114498Y-196188D01*
X1114280Y-197939D01*
X1113406Y-199397D01*
X1109040Y-202314D01*
X1107075Y-204355D01*
X1105765Y-207273D01*
X1105328Y-209897D01*
X1114498D01*
G01X1000110Y-164897D02*
Y-147397D01*
X1004476D01*
X1006223Y-148272D01*
X1007533Y-149439D01*
X1008625Y-151188D01*
X1009498Y-153231D01*
X1009716Y-156147D01*
X1009498Y-159064D01*
X1008625Y-161106D01*
X1007533Y-162856D01*
X1006223Y-164022D01*
X1004476Y-164897D01*
X1000110D01*
G01X1026343D02*
Y-153231D01*
G01Y-155272D02*
X1025470Y-154106D01*
X1024159Y-153522D01*
X1022631Y-153231D01*
X1021103Y-153814D01*
X1019793Y-154980D01*
X1018919Y-156730D01*
X1018483Y-159064D01*
X1018919Y-161397D01*
X1019793Y-163147D01*
X1021103Y-164314D01*
X1022631Y-164897D01*
X1024159Y-164605D01*
X1025470Y-163731D01*
X1026343Y-162564D01*
G01X1039913Y-147397D02*
Y-164897D01*
G01X1036856Y-153231D02*
X1042970D01*
G01X1054138Y-157022D02*
X1061125D01*
X1060470Y-154980D01*
X1059378Y-153814D01*
X1057850Y-153231D01*
X1056321Y-153522D01*
X1055011Y-154397D01*
X1054138Y-156439D01*
X1053701Y-158189D01*
Y-159939D01*
X1054138Y-161689D01*
X1055230Y-163439D01*
X1056540Y-164605D01*
X1058068Y-164897D01*
X1059596Y-164314D01*
X1061125Y-162564D01*
G54D11*
X17600Y5604D03*
X10000Y16500D03*
X11999Y53550D03*
X11499Y34050D03*
X11999Y69050D03*
Y88550D03*
X11499Y106050D03*
X11999Y124550D03*
X11499Y142050D03*
X11999Y177050D03*
Y161550D03*
Y196550D03*
X11499Y214050D03*
X9499Y229050D03*
X8999Y246550D03*
X9499Y281550D03*
Y266050D03*
Y301050D03*
X15499Y328050D03*
X8999Y318550D03*
X15499Y342550D03*
Y360050D03*
X14799Y751450D03*
X8599Y751650D03*
X17299Y773950D03*
X10999Y774050D03*
X8999Y889550D03*
X8499Y907050D03*
X8999Y942050D03*
Y926550D03*
Y961550D03*
X8499Y979050D03*
X8999Y988550D03*
Y1025550D03*
X8499Y1006050D03*
X8999Y1041050D03*
Y1060550D03*
X8499Y1089050D03*
Y1078050D03*
X7999Y1106550D03*
X8499Y1126050D03*
Y1141550D03*
Y1161050D03*
X7999Y1192550D03*
Y1178550D03*
X7499Y1210050D03*
X7999Y1229550D03*
Y1245050D03*
Y1264550D03*
X7499Y1282050D03*
X8299Y1320050D03*
X8799Y1302550D03*
X18099Y1343550D03*
X9399Y1347350D03*
X15299Y1723450D03*
X15399Y1708350D03*
X7099Y1717750D03*
X7199Y1731450D03*
X14899Y1736250D03*
X15299Y1753250D03*
X6099Y1753750D03*
X11299Y1850050D03*
X9099Y1881550D03*
X8499Y1979550D03*
X11500Y1987000D03*
X36000Y5604D03*
X23499Y27050D03*
X40999Y27550D03*
X27799Y38450D03*
X40999Y42050D03*
X25799Y64050D03*
X28399Y94950D03*
X34999Y108550D03*
X41399Y134150D03*
X27999Y131050D03*
Y145550D03*
Y163050D03*
X23999Y243550D03*
Y229050D03*
Y261050D03*
X39999Y327550D03*
Y342050D03*
Y359550D03*
Y576550D03*
X36999Y725050D03*
Y719550D03*
X37499Y714050D03*
X41499Y719550D03*
X26399Y750850D03*
X36499Y740050D03*
Y732550D03*
X39899Y754850D03*
X39399Y768750D03*
X27199Y764950D03*
X28599Y775450D03*
X26799Y874550D03*
X26099Y891650D03*
X25699Y916150D03*
X25099Y942150D03*
X23899Y957950D03*
X24799Y992250D03*
X33899Y1005950D03*
X21499Y1073250D03*
X21399Y1090850D03*
X21299Y1300250D03*
X21799Y1282750D03*
X31499Y1849750D03*
X39399Y1864350D03*
X23999Y1857950D03*
X27199Y1874350D03*
X34799Y1890050D03*
X26500Y1987000D03*
X55700Y5900D03*
X50999Y21150D03*
Y47750D03*
X59499Y90550D03*
Y76050D03*
Y108050D03*
X52499Y130550D03*
Y145050D03*
Y162550D03*
X41699Y183250D03*
X48499Y243050D03*
Y228550D03*
Y260550D03*
X42999Y275650D03*
X51099Y300050D03*
X52199Y342350D03*
X42299Y564150D03*
X62055Y561550D03*
X49555Y563550D03*
X61099Y603236D03*
X52333Y641295D03*
X43499Y657550D03*
X47800Y692800D03*
X53210Y701486D03*
X50999Y720050D03*
X46499Y719550D03*
X51499Y724550D03*
X46499D03*
X41999D03*
X46499Y730550D03*
X41999Y735050D03*
Y731050D03*
X46499Y735050D03*
X41999Y739550D03*
X46499Y739050D03*
X51999Y767050D03*
X47999Y767550D03*
X52499Y771550D03*
X47999D03*
X53999Y791000D03*
X52999Y1871550D03*
X57499Y1871050D03*
X45699Y1875550D03*
X47499Y1915050D03*
Y1930550D03*
X62499Y1939550D03*
X58999Y1958050D03*
X61500Y1987500D03*
X44500Y1987000D03*
X55999Y1982550D03*
X73900Y6200D03*
X65499Y27050D03*
Y41550D03*
Y59050D03*
X77165Y110799D03*
X71015Y123666D03*
X78165Y137116D03*
X75299Y261750D03*
X76099Y414250D03*
X75300Y454100D03*
X67300Y450200D03*
X68899Y445450D03*
X66099Y500950D03*
X77165Y514650D03*
X70800Y540300D03*
X75999Y556640D03*
X72599Y578236D03*
X79299Y794150D03*
X67999Y790400D03*
X76399Y820450D03*
X70100Y818900D03*
X77499Y921550D03*
X77002Y952079D03*
X76711Y948089D03*
X77499Y962152D03*
X72799Y982950D03*
X65799Y994050D03*
X67000Y1011500D03*
X77165Y1327335D03*
X77166Y1353400D03*
X76499Y1507050D03*
Y1498050D03*
Y1512050D03*
Y1503050D03*
X76999Y1528050D03*
Y1519050D03*
X81499Y1589050D03*
X83499Y1594050D03*
X78999Y1593550D03*
X74999D03*
X74499Y1602050D03*
Y1598050D03*
X83499D03*
Y1602050D03*
X78999Y1598050D03*
Y1602050D03*
X83599Y1744750D03*
X77165Y1759550D03*
X78529Y1788113D03*
X78999Y1891550D03*
X82999D03*
Y1887550D03*
X78999D03*
X62999Y1914550D03*
X78999Y1896050D03*
X78433Y1900010D03*
X78999Y1904050D03*
X83499Y1896050D03*
X83433Y1904010D03*
X62999Y1926050D03*
X81499Y1915550D03*
X82499Y1957050D03*
X73499D03*
X66499D03*
X73499Y1945550D03*
X79500Y1987500D03*
X65499Y1982550D03*
X73499D03*
X82999D03*
X90900Y5800D03*
X90899Y14850D03*
X96999Y49550D03*
X92999Y52050D03*
X97800Y36000D03*
X96900Y40400D03*
X93000Y44900D03*
X92900Y39700D03*
X95814Y136065D03*
X96184Y151065D03*
Y166065D03*
X97999Y199050D03*
X92899Y231450D03*
X86899Y242750D03*
X93199Y279650D03*
X84899Y289250D03*
X90899Y309550D03*
X94199Y325550D03*
X93499Y337450D03*
X89899Y368350D03*
X95499Y355450D03*
X89999Y396450D03*
X87599Y403950D03*
X95399Y416350D03*
X89099Y426150D03*
X99399Y437450D03*
X93500Y445300D03*
X97699Y449850D03*
X93199D03*
X97999Y445550D03*
X94500Y456800D03*
X100500Y456700D03*
X98999Y488050D03*
X94499Y486550D03*
X93499Y477050D03*
X97699Y481550D03*
Y477050D03*
X93499Y481550D03*
X101500Y536500D03*
X93599Y581236D03*
X93100Y571640D03*
X92599Y606236D03*
X98001Y856950D03*
X97800Y851800D03*
X93808Y852063D03*
X94001Y856895D03*
X97499Y862050D03*
X93299D03*
X93499Y897152D03*
X93900Y882400D03*
X97900D03*
X97700Y887400D03*
X93690Y887139D03*
X97499Y892550D03*
X93499Y892050D03*
X93000Y907165D03*
X83988Y934028D03*
X86700Y982100D03*
X100999Y1101050D03*
X104999D03*
X100999Y1096550D03*
X102999Y1188050D03*
X104999Y1231050D03*
X100999Y1231032D03*
X103499Y1305050D03*
X93316Y1351000D03*
X96000Y1369000D03*
X96100Y1384650D03*
X97300Y1564100D03*
X92499Y1589050D03*
X86999D03*
X90999Y1628550D03*
Y1624550D03*
X91121Y1632549D03*
X86299Y1632550D03*
X85999Y1628550D03*
Y1624550D03*
X84099Y1737150D03*
X93499Y1759550D03*
X94336Y1773113D03*
X104417Y1791480D03*
X97999Y1815050D03*
X104500Y1813400D03*
X83999Y1900050D03*
Y1945050D03*
X98433Y1940510D03*
X98999Y1944550D03*
X102433Y1940555D03*
X103433Y1944510D03*
X92499Y1959050D03*
X101699Y1983850D03*
X98000Y1987500D03*
X91499Y1983050D03*
X107000Y6000D03*
X116400Y56000D03*
X114800Y68500D03*
X123499Y149050D03*
Y140050D03*
X117500Y162300D03*
X124300Y167800D03*
X109499Y410250D03*
X124899Y409050D03*
X126099Y396150D03*
X111299Y425850D03*
X122499Y427900D03*
X108599Y557236D03*
X108900Y587600D03*
X112200Y762200D03*
X112000Y773000D03*
X111299Y821050D03*
X112999Y901150D03*
X106500Y943000D03*
X105300Y960300D03*
X105006Y1096866D03*
X110999Y1130550D03*
X115200Y1130300D03*
X110999Y1126050D03*
Y1122050D03*
Y1118050D03*
X114999Y1126050D03*
Y1122050D03*
Y1118050D03*
X106999Y1114960D03*
X120999Y1188050D03*
X111999D03*
X121657Y1224604D03*
X120999Y1228550D03*
X120499Y1264550D03*
X123938Y1267623D03*
X117149Y1267550D03*
X123500Y1360300D03*
X122600Y1565000D03*
X124999Y1616050D03*
Y1620050D03*
Y1629050D03*
Y1633050D03*
X119999Y1629050D03*
X120100Y1633100D03*
X122499Y1668550D03*
Y1672550D03*
X118999Y1670550D03*
X105749Y1712749D03*
X117499Y1745050D03*
X123499Y1747050D03*
X120299Y1796150D03*
X111499Y1877550D03*
Y1882550D03*
X122999Y1883050D03*
X115999Y1882550D03*
X116499Y1877550D03*
X122999Y1889050D03*
X124433Y1908510D03*
X124999Y1912550D03*
X119999Y1978550D03*
X119499Y1972550D03*
X108499Y1981750D03*
X115000Y1987000D03*
X129100Y55900D03*
X127499Y65050D03*
X141999Y65550D03*
X129999Y78050D03*
X127999Y99550D03*
X133999Y149050D03*
X142999Y141050D03*
X132999Y141550D03*
X144499Y149050D03*
X131799Y201950D03*
X142688Y218861D03*
X143110Y203861D03*
X133000Y240500D03*
X135399Y277050D03*
X130799Y300250D03*
X130099Y326150D03*
X134699Y356050D03*
X139399Y372350D03*
X127999Y425050D03*
Y421050D03*
Y429550D03*
X133499Y445050D03*
X128999Y445550D03*
X130000Y452000D03*
X135999Y472550D03*
X135140Y478930D03*
X139200Y484300D03*
X134499Y488050D03*
X145649Y509550D03*
X136349Y509050D03*
X140499Y499050D03*
X136299D03*
X147300Y526700D03*
X140000Y587700D03*
X140499Y600550D03*
X143999Y605550D03*
X140499Y626050D03*
X131099Y700450D03*
X139099Y707150D03*
X141234Y1029885D03*
X140864Y1044885D03*
X137900Y1103400D03*
X139100Y1097100D03*
X134500Y1108100D03*
X143200Y1116300D03*
X133200Y1132100D03*
X126400Y1138100D03*
X145900Y1163200D03*
X144399Y1171150D03*
X141499Y1185550D03*
X128400Y1188600D03*
X143899Y1196750D03*
X142499Y1205550D03*
X130999Y1198050D03*
X144149Y1230113D03*
Y1226113D03*
Y1222113D03*
X126499Y1264550D03*
X145999Y1353050D03*
X143199Y1412050D03*
X140799Y1435460D03*
X129100Y1564700D03*
X127200Y1569800D03*
X126562Y1670613D03*
X130499Y1730050D03*
X128000Y1735000D03*
X144499Y1729550D03*
X139500Y1730500D03*
X133000Y1734500D03*
X144499Y1745550D03*
X137999Y1747723D03*
X129999Y1747050D03*
X126599Y1789650D03*
X142144Y1801644D03*
X143490Y1855972D03*
X127499Y1889050D03*
X126999Y1882550D03*
X142499Y1905972D03*
X141499Y1895972D03*
X129999Y1908550D03*
X129433Y1912510D03*
X127499Y1978550D03*
X133499D03*
X132999Y1972550D03*
X126999D03*
X146899Y1961750D03*
X146000Y1987500D03*
X128500D03*
X157299Y5150D03*
X167499Y43550D03*
X156499Y66050D03*
X166999Y88050D03*
X166499Y83550D03*
Y79050D03*
X158499D03*
Y84050D03*
Y88550D03*
Y93550D03*
X166999Y92550D03*
X165499Y106050D03*
X166999Y97050D03*
X152999Y141050D03*
X167499Y149550D03*
X163499Y140050D03*
X160999Y149550D03*
X155999Y181050D03*
X166800Y240800D03*
X158999Y259800D03*
X152808Y246341D03*
X157740Y273924D03*
X167299Y369350D03*
X150699Y411050D03*
X152499Y395950D03*
X149700Y471600D03*
X154100Y476500D03*
X164600Y476700D03*
X153499Y502550D03*
X148999D03*
X147590Y521500D03*
X154099Y529236D03*
X162500Y623400D03*
X152400Y643300D03*
X152124Y651868D03*
X159054Y665400D03*
X161999Y768050D03*
X152499Y810550D03*
Y816050D03*
Y820550D03*
Y825050D03*
X161999Y843550D03*
Y848050D03*
X156499Y846050D03*
X156999Y850050D03*
X156499Y870550D03*
Y876050D03*
X163999Y863050D03*
X159999D03*
X155999Y859050D03*
Y863050D03*
X158114Y883290D03*
X156499Y886950D03*
X159459Y896616D03*
X163499Y896550D03*
X155499Y891050D03*
Y896050D03*
X157499Y904550D03*
Y909050D03*
X151999Y936550D03*
X152499Y931550D03*
X153299Y943750D03*
X159186Y946117D03*
X156499Y985950D03*
X149499Y997650D03*
X162499Y1023550D03*
X158300Y1015000D03*
X163499Y1035050D03*
X159499Y1044579D03*
X151300Y1049300D03*
X165600Y1057428D03*
X168099Y1083550D03*
X164999Y1075550D03*
X159055Y1070400D03*
X167999Y1092850D03*
X167499Y1118550D03*
X167999Y1130550D03*
X163499Y1171650D03*
X151699Y1158550D03*
X151499Y1173050D03*
X150999Y1181150D03*
X148499Y1222113D03*
Y1226113D03*
X148486Y1230113D03*
X167499Y1389050D03*
X156999Y1397750D03*
X166799Y1409350D03*
X157915Y1420460D03*
X163499Y1433350D03*
X165499Y1453550D03*
X166799Y1487450D03*
X159054Y1476200D03*
X167499Y1714113D03*
X162499D03*
X165499Y1730613D03*
X167999Y1726613D03*
X163499D03*
X157500Y1797400D03*
X158000Y1825400D03*
X157999Y1840972D03*
X167200Y1868000D03*
X159054Y1855050D03*
X163599Y1892050D03*
X168299Y1879850D03*
X159054Y1881800D03*
X159173Y1935972D03*
X148499Y1977250D03*
X163500Y1987500D03*
X189499Y4550D03*
Y39150D03*
X183499Y45550D03*
X168499Y65550D03*
X169999Y103050D03*
X176499Y140050D03*
X177899Y199250D03*
X185999Y250550D03*
X181299Y267350D03*
X187199Y359050D03*
X181599Y396250D03*
X168999Y413050D03*
X188499Y413550D03*
X179999Y442550D03*
X179649Y438550D03*
X183999D03*
Y442550D03*
Y447050D03*
X179999D03*
X171300Y476700D03*
X187499Y531613D03*
Y536113D03*
X188999Y541113D03*
Y549613D03*
Y545613D03*
X181999Y624050D03*
Y609550D03*
Y641550D03*
X182599Y688350D03*
X171999Y672450D03*
X170799Y689150D03*
X178899Y765250D03*
X172599Y774250D03*
X168499Y846713D03*
X173899Y846550D03*
X172099Y877450D03*
X169299Y956350D03*
X171499Y998650D03*
X169299Y1067150D03*
X171599Y1139950D03*
X180400Y1202800D03*
X181700Y1219900D03*
X179800Y1244100D03*
X179500Y1262000D03*
X175823Y1297070D03*
X179999Y1301550D03*
Y1292550D03*
X175499D03*
X179999Y1296613D03*
X175499Y1302113D03*
X179999Y1306050D03*
X175499Y1306113D03*
X178200Y1393400D03*
X180599Y1424050D03*
X180000Y1439500D03*
X176599Y1447450D03*
X172299Y1465850D03*
X181500Y1479000D03*
X176299Y1500150D03*
X180299Y1626550D03*
X180000Y1619600D03*
X180299Y1634550D03*
X179733Y1630590D03*
X181900Y1675300D03*
X180701Y1716050D03*
X179701Y1724550D03*
X172499Y1714050D03*
X180000Y1731000D03*
X170499Y1731050D03*
X172499Y1726613D03*
X185999Y1746050D03*
X182299Y1801350D03*
X173899Y1813250D03*
X177599Y1866750D03*
X168499Y1855550D03*
X181099Y1885850D03*
X168699Y1957150D03*
X183999Y1968150D03*
X188199Y1978250D03*
X183000Y1987500D03*
X206999Y5050D03*
X197999Y39900D03*
X193999D03*
X208499Y45650D03*
X199999Y46050D03*
X194499Y44050D03*
X191999Y68050D03*
X192499Y57550D03*
X206899Y171650D03*
X190199Y178650D03*
X191999Y221550D03*
X203499Y250550D03*
X201199Y266750D03*
X209199Y365050D03*
X209499Y412550D03*
X209999Y426150D03*
X194999Y490050D03*
X190499Y487550D03*
X191199Y491550D03*
X205300Y508100D03*
X190499Y507513D03*
X193499Y541113D03*
Y549613D03*
X193999Y545550D03*
X206499Y623550D03*
Y609050D03*
X207300Y639400D03*
X199199Y659150D03*
X190399Y689050D03*
X209500Y759000D03*
X208799Y766750D03*
X190699Y778350D03*
X197099Y795050D03*
X208299Y805350D03*
X202900Y811900D03*
X198199Y805950D03*
X204496Y846111D03*
X204649Y838050D03*
X208999D03*
X209000Y846113D03*
X204649Y842113D03*
X208986D03*
X198499Y884113D03*
X204699Y929450D03*
X206699Y953050D03*
X203999Y943350D03*
X205999Y978250D03*
X206299Y990250D03*
X207299Y1008150D03*
X202100Y1028100D03*
X199499Y1093850D03*
X209900Y1093600D03*
X208199Y1145850D03*
X210199Y1173450D03*
X204199Y1163850D03*
X201600Y1205900D03*
X196499Y1215550D03*
Y1196550D03*
X196399Y1236650D03*
X196499Y1224550D03*
X195499Y1251050D03*
X202199Y1276850D03*
X195499Y1279050D03*
Y1270050D03*
X202899Y1291450D03*
X207699Y1337950D03*
X195500Y1352500D03*
X208049Y1385550D03*
X203199Y1393250D03*
X204699Y1418350D03*
X201000Y1408500D03*
X194200Y1457900D03*
X204999Y1472650D03*
X208999Y1491250D03*
X202399Y1500750D03*
X195700Y1619100D03*
X195600Y1623700D03*
X209200Y1624000D03*
X200600Y1663600D03*
X199900Y1670600D03*
X193499Y1674050D03*
X197600Y1694900D03*
X204400Y1688200D03*
X209901Y1691850D03*
X201801Y1701450D03*
X195001Y1708150D03*
X205200Y1708000D03*
X195500Y1717000D03*
X195000Y1725500D03*
X206900Y1726700D03*
X199699Y1761450D03*
X205199Y1801950D03*
X209999Y1825050D03*
X192100Y1813500D03*
X204399Y1855450D03*
X206999Y1867550D03*
X207199Y1892850D03*
X191599Y1891550D03*
X199599Y1879850D03*
X205499Y1968650D03*
X190199Y1957650D03*
X199600Y1974900D03*
X209699Y1978750D03*
X199000Y1987500D03*
X226499Y5050D03*
X225499Y52550D03*
Y46550D03*
Y63550D03*
Y58050D03*
X229099Y161350D03*
X227999Y178050D03*
X227499Y192050D03*
X227999Y187050D03*
Y182550D03*
X210999Y221550D03*
X217999Y250550D03*
X223799Y365350D03*
X217599Y396450D03*
X218499Y474850D03*
X224299Y494650D03*
X220499Y560050D03*
Y545550D03*
Y577550D03*
X224999Y613450D03*
X219999Y632550D03*
Y647050D03*
X226399Y677550D03*
X212999Y677350D03*
X218800Y668700D03*
X224099Y770250D03*
X214799Y774750D03*
X227199Y795050D03*
X217300Y816800D03*
X215999Y887550D03*
X220499D03*
X215499Y883550D03*
X219499Y939613D03*
X214999D03*
X219499Y926613D03*
X214999D03*
X225299Y957650D03*
X213999Y958650D03*
X219499Y948613D03*
Y943813D03*
X214999Y944113D03*
Y948613D03*
X217499Y981050D03*
X216999Y967550D03*
X217499Y998550D03*
X217999Y1012050D03*
X215999Y1039550D03*
X216499Y1053050D03*
X214499Y1154250D03*
X223099Y1182750D03*
X212499Y1184550D03*
Y1212550D03*
X221599Y1237250D03*
X220999Y1224350D03*
X222299Y1251850D03*
X229899Y1250550D03*
X211499Y1258050D03*
Y1239050D03*
X216300Y1274800D03*
X211499Y1267050D03*
X219099Y1325950D03*
X226599Y1340250D03*
X213199Y1350050D03*
X227399Y1363050D03*
X217499Y1387450D03*
X230599Y1400250D03*
X217999Y1408850D03*
X227999Y1421550D03*
X226300Y1447800D03*
X230899Y1437350D03*
X212400Y1433700D03*
X213399Y1500300D03*
X212899Y1535550D03*
X230999D03*
X211999Y1568550D03*
X231499Y1575050D03*
X224499D03*
X217999Y1574550D03*
X211999D03*
X218000Y1614300D03*
X228999Y1637550D03*
X211999Y1653550D03*
X230600Y1670500D03*
X213000Y1672500D03*
X216601Y1684350D03*
X226800Y1684200D03*
X220100Y1691700D03*
X212000Y1701300D03*
X222700Y1710100D03*
X222499Y1743850D03*
X221499Y1760950D03*
X220799Y1791550D03*
X215299Y1813950D03*
X224800Y1867000D03*
X228999Y1856050D03*
X212399Y1885850D03*
X226999Y1941050D03*
X227499Y1971050D03*
X221300Y1971200D03*
X225199Y1978750D03*
X216999Y1987550D03*
X241999Y5050D03*
X247499Y37550D03*
X246999Y46550D03*
Y56050D03*
X247499Y65050D03*
X244499Y136550D03*
Y122050D03*
X244900Y149100D03*
X231999Y178050D03*
Y192050D03*
Y187050D03*
Y182550D03*
X232400Y220700D03*
X249800Y248800D03*
X235399Y263350D03*
X237699Y426050D03*
X232999Y414550D03*
X252499Y415050D03*
X251499Y446050D03*
X231999Y445550D03*
X251999Y462050D03*
X232499Y461550D03*
X244199Y483350D03*
X242099Y511750D03*
X244999Y559550D03*
Y545050D03*
Y577050D03*
X244499Y632050D03*
X246500Y663300D03*
X245000Y647000D03*
X234200Y668300D03*
X245599Y773450D03*
X234299Y773750D03*
X247099Y795050D03*
X233799Y806350D03*
X245399Y823550D03*
X244099Y857450D03*
X252399Y838250D03*
X245199Y878050D03*
X232399Y886550D03*
X252899Y886350D03*
X245399Y907450D03*
X243899Y923650D03*
X242199Y938750D03*
X252499Y948850D03*
X244199Y973250D03*
X232299Y981950D03*
X233499Y966050D03*
X245899Y995250D03*
X233999Y997050D03*
Y1012550D03*
X232499Y1038050D03*
X249499Y1104150D03*
X232599Y1195750D03*
X251999Y1184550D03*
X242199Y1210050D03*
X242599Y1198350D03*
X247899Y1208650D03*
X234299Y1232650D03*
X250900Y1248500D03*
X242900Y1263000D03*
X232799Y1276150D03*
X241399Y1303250D03*
X239099Y1314150D03*
X252399Y1326350D03*
X245999Y1339050D03*
Y1358050D03*
X234300Y1375700D03*
X246499Y1370050D03*
X249800Y1388400D03*
X244999Y1412550D03*
X245499Y1424550D03*
X238899Y1453750D03*
X248000Y1482000D03*
X250199Y1473550D03*
X247500Y1499000D03*
X236999Y1535550D03*
X238300Y1575100D03*
X246200Y1617600D03*
X239400Y1624300D03*
X242999Y1658050D03*
X237400Y1663800D03*
X235499Y1697050D03*
X249199Y1743150D03*
X237999Y1730550D03*
X244999Y1755050D03*
X252199Y1793050D03*
X238699Y1801850D03*
X241199Y1867150D03*
X244700Y1878700D03*
X241255Y1896055D03*
X238999Y1970550D03*
X232999Y1971050D03*
X240900Y1979000D03*
X236500Y1987500D03*
X261499Y4550D03*
X253999Y48050D03*
X264999Y55350D03*
X261299Y75950D03*
X258699Y104550D03*
X265299Y96250D03*
X262299Y164050D03*
X262699Y208550D03*
X271999Y216050D03*
X265999Y245050D03*
X267498Y305114D03*
Y300114D03*
Y295114D03*
Y310114D03*
X258999Y396650D03*
X266699Y425050D03*
X269999Y415050D03*
X272499Y445050D03*
X266199Y472350D03*
X272999Y461050D03*
X257499Y498050D03*
Y512550D03*
Y530050D03*
X256499Y577050D03*
Y591550D03*
Y609050D03*
X269499Y616550D03*
X257199Y640050D03*
X269499Y631050D03*
Y648550D03*
X268499Y701550D03*
Y706550D03*
Y716550D03*
Y711550D03*
X268099Y795450D03*
X254699Y807650D03*
X264499Y829050D03*
X264999Y842550D03*
Y858450D03*
X265799Y901850D03*
X256199Y916250D03*
X254899Y929250D03*
X253499Y938050D03*
X269599Y923950D03*
X267199Y935350D03*
X264799Y946850D03*
X263299Y959350D03*
X272999Y981050D03*
Y965550D03*
X256499Y967050D03*
X262499Y995850D03*
X254499Y984550D03*
X258999Y1011550D03*
X269999Y1037050D03*
X253499Y1038550D03*
X269999Y1052550D03*
X253999Y1052050D03*
X272999Y1102850D03*
X262499Y1129150D03*
X260349Y1139200D03*
X272499Y1153050D03*
X268499D03*
X263999D03*
X259999Y1152992D03*
X271999Y1161550D03*
X267999D03*
X263499D03*
X259499D03*
X272999Y1214150D03*
X261199Y1227950D03*
X264800Y1261300D03*
X254899Y1289950D03*
X264799Y1313850D03*
X265299Y1339650D03*
X263699Y1359550D03*
X265499Y1376950D03*
X258999Y1396950D03*
X270599Y1408550D03*
X259299Y1438750D03*
X268499Y1453550D03*
X260999Y1503550D03*
X266999Y1512550D03*
X267349Y1518150D03*
Y1522550D03*
Y1527172D03*
X265700Y1635100D03*
X258700Y1645100D03*
X270999Y1660550D03*
X253999Y1676550D03*
X273499Y1694050D03*
X255699Y1722550D03*
X256499Y1710050D03*
X263499Y1734550D03*
X270599Y1748950D03*
X259499Y1760650D03*
X270599Y1801450D03*
X253899Y1813250D03*
X261499Y1825050D03*
X255999Y1855950D03*
X270299Y1867250D03*
X266999Y1915550D03*
Y1920050D03*
Y1924550D03*
Y1929050D03*
Y1933550D03*
X254500Y1987500D03*
X272000D03*
X278999Y5050D03*
X292999Y4550D03*
X294100Y28000D03*
X289499Y39050D03*
X286603Y34928D03*
X289999Y72550D03*
X290999Y67550D03*
X288499Y76550D03*
X289499Y80550D03*
X283599Y106250D03*
X274700Y131500D03*
X280999Y120050D03*
Y152050D03*
X290999Y216050D03*
X283499Y245050D03*
X279998Y304114D03*
Y299614D03*
Y295114D03*
Y308614D03*
X277799Y338599D03*
X293998Y361114D03*
Y356614D03*
Y352114D03*
X289998Y361114D03*
Y356614D03*
Y352114D03*
X276299Y376050D03*
X289399Y395750D03*
X284499Y415050D03*
X291599Y446150D03*
X286999Y462050D03*
X281999Y497550D03*
X292999Y483550D03*
X281999Y512050D03*
Y529550D03*
X277999Y545350D03*
X280999Y576550D03*
Y591050D03*
Y608550D03*
X293999Y616050D03*
Y630550D03*
Y648050D03*
X280999Y701550D03*
Y705550D03*
Y717550D03*
X280433Y713590D03*
X294999Y767050D03*
X290999D03*
X294999Y762550D03*
Y758050D03*
X290999Y762550D03*
Y758050D03*
X287799Y794850D03*
X275299Y806350D03*
X288899Y820550D03*
X280999Y827550D03*
X283599Y857450D03*
X293899Y843850D03*
X280999Y843050D03*
Y870050D03*
X281499Y883550D03*
X274299Y912950D03*
X287299Y901050D03*
X281099Y943550D03*
X278799Y956150D03*
X290099Y948650D03*
X289399Y963350D03*
X277599Y975250D03*
X288099Y971250D03*
X285399Y982950D03*
X294699Y989550D03*
X287099Y1000150D03*
X274999Y996550D03*
X289699Y1021750D03*
X275099Y1024750D03*
X274999Y1012050D03*
X287099Y1035050D03*
X282999Y1099550D03*
X274900Y1115600D03*
X290699Y1122650D03*
X283499Y1113050D03*
X276299Y1134550D03*
X283299Y1144850D03*
X291399Y1174150D03*
X279799Y1191750D03*
X286599Y1203750D03*
X283799Y1249250D03*
X274299Y1276450D03*
X281099Y1302850D03*
X286799Y1326450D03*
X286499Y1364050D03*
Y1345050D03*
X278799Y1386250D03*
X285499Y1399550D03*
X278000Y1422000D03*
X285499Y1418550D03*
Y1427550D03*
X286600Y1449700D03*
X279499Y1510550D03*
X286700Y1516100D03*
X279499Y1515050D03*
X279075Y1525957D03*
X278567Y1529925D03*
X293998Y1573614D03*
Y1569114D03*
X289998Y1573614D03*
Y1569114D03*
X293998Y1578114D03*
X289998D03*
X278499Y1621550D03*
X289000Y1641800D03*
X284300Y1676900D03*
X291099Y1707450D03*
X280499Y1718550D03*
X285499Y1742550D03*
X290699Y1760750D03*
X286599Y1791850D03*
X284299Y1811150D03*
X295299Y1870250D03*
X283999Y1856050D03*
X293999Y1933050D03*
X281999Y1918550D03*
Y1923550D03*
Y1928550D03*
X293999Y1971050D03*
Y1966550D03*
Y1962050D03*
X289499Y1961550D03*
Y1966550D03*
Y1971050D03*
X291499Y1987550D03*
X310499Y5050D03*
X304500Y44500D03*
X303300Y39500D03*
X308700Y39800D03*
X308800Y46400D03*
X306999Y55450D03*
X311299D03*
X315799Y55350D03*
X308499Y72550D03*
X303999Y74050D03*
X307999Y78550D03*
X306100Y126500D03*
X307199Y205550D03*
X310499Y216550D03*
X297999Y245050D03*
X313199Y270350D03*
X313000Y313900D03*
X305998Y352114D03*
X299899Y376650D03*
X310999Y396250D03*
X300899Y431850D03*
X303999Y415550D03*
X306100Y462000D03*
X312499Y484050D03*
X298599Y501250D03*
X309399Y513450D03*
X297599Y519350D03*
X307499Y555550D03*
Y541050D03*
X297499Y551050D03*
X296199Y568550D03*
X307499Y573050D03*
X302899Y607950D03*
X307499Y661550D03*
Y647050D03*
X297699Y681850D03*
X307499Y679050D03*
X308899Y705150D03*
X298399Y703450D03*
X296399Y716950D03*
X306999Y758050D03*
X314499Y754550D03*
X307999Y803150D03*
X307899Y794550D03*
X300199Y835250D03*
X304899Y856150D03*
X313499Y847850D03*
X315199Y869450D03*
X297499Y868550D03*
X302499Y899050D03*
X297499Y884050D03*
X302199Y914650D03*
X315199Y925950D03*
X310699Y943550D03*
X299399Y965950D03*
X298099Y977250D03*
X307999Y970650D03*
X306699Y981250D03*
X304399Y997550D03*
X298399Y1008150D03*
X306399Y1020750D03*
X303699Y1038050D03*
X299999Y1052350D03*
X304699Y1057050D03*
X312299Y1093550D03*
X299499Y1098050D03*
Y1113550D03*
X316499Y1124550D03*
X307999Y1142050D03*
X304499Y1156650D03*
X313499Y1170150D03*
X300699Y1185150D03*
X315408Y1202663D03*
X311999Y1213850D03*
X300699Y1227350D03*
X310299Y1240050D03*
X304699Y1265850D03*
X312499Y1280350D03*
X295399Y1292950D03*
X300499Y1305350D03*
X311500Y1316300D03*
X297899Y1336150D03*
X298099Y1357250D03*
X311900Y1344900D03*
X301699Y1377950D03*
X312900Y1366900D03*
X301699Y1395750D03*
X313600Y1391300D03*
X303499Y1411250D03*
X312100Y1420700D03*
X300899Y1433350D03*
X313600Y1442700D03*
X304699Y1457550D03*
X312800Y1467400D03*
X296599Y1497150D03*
X312000Y1514600D03*
X305998Y1569114D03*
X307000Y1619600D03*
X302399Y1662950D03*
X299999Y1696050D03*
X303999Y1722050D03*
X297099Y1733850D03*
X303499Y1753550D03*
X303999Y1800850D03*
X315499Y1812250D03*
X298999Y1855950D03*
X313599Y1870250D03*
X308099Y1880550D03*
X313599Y1889250D03*
X314099Y1901250D03*
X305999Y1913050D03*
X306999Y1932550D03*
X302499D03*
X298499D03*
X302499Y1922050D03*
X296858Y1956228D03*
X305999Y1964050D03*
Y1969550D03*
X311500Y1987500D03*
X329999Y5050D03*
X332200Y94200D03*
X321799Y173950D03*
X317499Y192950D03*
X331499Y193250D03*
X325499Y249450D03*
X337499Y282550D03*
X316999Y312576D03*
X321748Y343299D03*
X328799Y372350D03*
X336099Y417550D03*
X322099Y426850D03*
X324999Y414550D03*
X328599Y442250D03*
X327900Y463200D03*
X333499Y483050D03*
X329999Y510450D03*
X321999Y533150D03*
X331999Y555050D03*
Y540550D03*
X321999Y550550D03*
X321299Y565250D03*
X320799Y582050D03*
X331999Y572550D03*
X328599Y602450D03*
X328499Y635650D03*
X317999Y627850D03*
X331999Y661050D03*
Y646550D03*
Y678550D03*
X324599Y696150D03*
X330799Y712450D03*
X318999Y814350D03*
X325599Y823950D03*
X330299Y871850D03*
X323799Y859850D03*
X321099Y899650D03*
X323099Y885050D03*
X322099Y913650D03*
X331099Y923650D03*
X328099Y937250D03*
X323499Y956950D03*
X329799Y970650D03*
X333099Y983450D03*
X320999Y997250D03*
X331299Y1017150D03*
X321299Y1012450D03*
Y1024750D03*
X331599Y1028750D03*
X329599Y1040750D03*
X318299Y1038750D03*
X329599Y1057050D03*
X319999Y1066950D03*
X317699Y1054650D03*
X329299Y1098550D03*
X326599Y1112350D03*
X332999Y1123050D03*
X323999Y1153250D03*
X332999Y1138550D03*
X317999Y1137550D03*
X329799Y1182750D03*
X328999Y1200550D03*
X326649Y1227850D03*
Y1218850D03*
X327999Y1255050D03*
X333349Y1270500D03*
Y1288900D03*
Y1307000D03*
Y1332800D03*
Y1363500D03*
Y1393100D03*
Y1429500D03*
Y1481900D03*
X332500Y1519700D03*
X337199Y1636350D03*
X320299Y1642950D03*
X316799Y1657450D03*
X335767Y1662735D03*
X318499Y1675550D03*
X334399Y1691650D03*
X329999Y1716950D03*
X320999Y1706050D03*
X321999Y1733050D03*
X326301Y1766030D03*
X321499Y1772550D03*
X327299Y1791850D03*
X322299Y1802150D03*
X334999Y1797050D03*
X337499Y1855950D03*
X316999D03*
X336799Y1869950D03*
X326399Y1876250D03*
X336799Y1888950D03*
X326899Y1907250D03*
X326399Y1895250D03*
X336799Y1897950D03*
X335799Y1916450D03*
X326799Y1977050D03*
X329999Y1987550D03*
X345499Y5050D03*
X356499Y113050D03*
X351999D03*
X347499D03*
X355999Y100550D03*
X350999D03*
X345999D03*
X354099Y175350D03*
X343399Y161350D03*
X343999Y190050D03*
X343799Y204550D03*
X355499Y219050D03*
X337999D03*
X355999Y242750D03*
X343499Y253550D03*
X347699Y269050D03*
X354999Y282550D03*
X347399Y301950D03*
X339399Y358050D03*
X357999Y359050D03*
X354099Y373050D03*
X338399Y395650D03*
X338899Y433850D03*
X354699Y426650D03*
X356399Y451750D03*
X351399Y470750D03*
X340799Y512050D03*
X358399Y498650D03*
X341399Y535850D03*
X357399Y521250D03*
Y530550D03*
X341399Y558950D03*
X357399Y543850D03*
X357999Y559450D03*
X340299Y586550D03*
X342199Y613050D03*
X342099Y646350D03*
X341899Y664950D03*
X342599Y678850D03*
X345399Y698950D03*
X357699Y707750D03*
X341399Y715050D03*
X355999Y752850D03*
X353999Y787750D03*
X347699Y773450D03*
X338099Y811650D03*
X338599Y821650D03*
Y840450D03*
X340099Y887350D03*
X338399Y901050D03*
X340099Y910350D03*
X340399Y931250D03*
X340099Y952850D03*
X339599Y1081550D03*
X344399Y1338150D03*
X343599Y1360050D03*
X344099Y1393750D03*
Y1421150D03*
Y1449550D03*
X351899Y1570850D03*
X344500Y1583600D03*
X350600Y1610900D03*
X349099Y1634550D03*
X351099Y1691150D03*
X352000Y1700400D03*
X343899Y1752650D03*
X357999Y1796050D03*
X355699Y1810750D03*
X351999Y1855450D03*
X348999Y1879050D03*
X349499Y1910050D03*
X348999Y1898050D03*
X347999Y1925550D03*
X348499Y1956550D03*
X347999Y1944550D03*
X347699Y1972250D03*
X345499Y1987550D03*
X364999Y4550D03*
X371999Y15550D03*
X376499D03*
X369999Y23550D03*
Y19050D03*
X376999Y65550D03*
Y70050D03*
X360999Y113050D03*
Y100550D03*
X363999Y136050D03*
Y121550D03*
Y153550D03*
X362999Y190050D03*
X369999Y219050D03*
X362499Y253550D03*
X369499Y282550D03*
X359399Y307250D03*
X368299Y386350D03*
X359399Y576050D03*
Y599650D03*
X360399Y615550D03*
X359699Y627550D03*
X358899Y657150D03*
X359399Y669450D03*
X359199Y690650D03*
X377499Y1182050D03*
Y1210050D03*
Y1201050D03*
X376499Y1236550D03*
Y1255550D03*
Y1264550D03*
X376599Y1293950D03*
X375599Y1323350D03*
X374499Y1347550D03*
Y1375550D03*
Y1366550D03*
X373499Y1402050D03*
Y1421050D03*
X376299Y1437650D03*
X373499Y1430050D03*
X373099Y1456550D03*
X374799Y1491250D03*
X374099Y1554550D03*
X376099Y1572850D03*
X375099Y1608250D03*
X377700Y1629000D03*
X374999Y1656750D03*
X377099Y1696350D03*
X359499Y1736850D03*
X376799Y1734050D03*
X376499Y1775550D03*
X369499Y1855950D03*
X359999Y1878550D03*
X369799Y1880050D03*
X359999Y1897550D03*
Y1906550D03*
X369999Y1901950D03*
X358999Y1925050D03*
X369199Y1919750D03*
X367299Y1956950D03*
X367999Y1940250D03*
X367299Y1972950D03*
X364999Y1987050D03*
X382499Y5050D03*
X395999Y5550D03*
X380999Y15550D03*
X382499Y20050D03*
X381499Y65550D03*
Y70050D03*
X389599Y90950D03*
X380599Y103550D03*
X381299Y136750D03*
X400499Y134050D03*
Y119550D03*
Y151550D03*
X389299Y161650D03*
X382499Y190550D03*
X387599Y220150D03*
X385999Y207250D03*
X381999Y254050D03*
X382999Y276650D03*
X386899Y299250D03*
X383299Y310250D03*
X386599Y348450D03*
X394899Y357750D03*
X380599Y381050D03*
X380099Y1709650D03*
X393499Y1759550D03*
X393999Y1784550D03*
X387899Y1802850D03*
X391499Y1855950D03*
X389499Y1885050D03*
Y1913050D03*
Y1904050D03*
X388499Y1932950D03*
Y1950550D03*
X385099Y1975950D03*
X399299Y1976750D03*
X388499Y1959550D03*
X382499Y1987550D03*
X413499Y6050D03*
X416999Y25050D03*
X417499Y46550D03*
X416999Y63550D03*
X417499Y79050D03*
Y93550D03*
Y108050D03*
Y125550D03*
X416999Y145050D03*
Y164050D03*
X417999Y185050D03*
X412999Y275550D03*
Y307550D03*
Y290050D03*
X422199Y363350D03*
X420199Y391350D03*
X415099Y422550D03*
X410799Y431150D03*
X419599Y458550D03*
X415999Y518550D03*
X420199Y638550D03*
X418799Y877050D03*
Y896050D03*
X409499Y1102550D03*
X419999Y1115550D03*
X415499Y1161550D03*
X416099Y1183550D03*
X415499Y1176050D03*
X419499Y1234050D03*
Y1219550D03*
X420099Y1241550D03*
X416699Y1342650D03*
X416199Y1367550D03*
X414799Y1532350D03*
X418299Y1561250D03*
X415999Y1603250D03*
X416199Y1625250D03*
X414799Y1653750D03*
X414399Y1678350D03*
X414499Y1707250D03*
X410757Y1772872D03*
X417799Y1790850D03*
X414499Y1810450D03*
X406999Y1855950D03*
X421399Y1888050D03*
X406499Y1893050D03*
Y1874050D03*
X421399Y1907050D03*
X406999Y1905050D03*
X420399Y1934550D03*
X421399Y1916050D03*
X405499Y1920550D03*
X420399Y1953550D03*
X405999Y1951550D03*
X405499Y1939550D03*
X420399Y1962550D03*
X420799Y1977250D03*
X420500Y1987000D03*
X403500D03*
X432999Y6050D03*
X436499Y31350D03*
Y50350D03*
X437499Y71350D03*
X441799Y102450D03*
Y121450D03*
X442799Y142450D03*
X430499Y217050D03*
X423799Y259750D03*
X437499Y275050D03*
Y307050D03*
Y289550D03*
X422499Y348150D03*
X438999Y381550D03*
X426599Y415350D03*
X443199Y440850D03*
X440099Y459250D03*
X431099Y479350D03*
X435499Y519050D03*
X430099Y551450D03*
X427999Y580050D03*
Y565550D03*
Y597550D03*
X427499Y624550D03*
X437299Y744650D03*
X435299Y763150D03*
X424999Y766550D03*
X435299Y777650D03*
X422999Y785050D03*
X434799Y814650D03*
X435299Y795150D03*
X422999Y799550D03*
X434799Y833650D03*
X422999Y817050D03*
X422499Y855550D03*
Y836550D03*
X442599Y905650D03*
Y924650D03*
X423299Y994050D03*
Y1013050D03*
X424299Y1034050D03*
X432599Y1064550D03*
X433599Y1085550D03*
X428999Y1102550D03*
X439499Y1115550D03*
X436999Y1128050D03*
X437599Y1150050D03*
X436999Y1142550D03*
X443199Y1224250D03*
Y1238750D03*
X424999Y1278550D03*
Y1259550D03*
X425499Y1290550D03*
X428499Y1325350D03*
X434499Y1360250D03*
X422299Y1394950D03*
X441499Y1399550D03*
X426799Y1416050D03*
X441499Y1414050D03*
X423299Y1430350D03*
X425799Y1447950D03*
X441499Y1431550D03*
X427099Y1469150D03*
X424299Y1541350D03*
X439599Y1552150D03*
X434500Y1579500D03*
X432499Y1617550D03*
X431999Y1605550D03*
X425499Y1635050D03*
X432400Y1680100D03*
X427499Y1662050D03*
X428600Y1691200D03*
X435300Y1715300D03*
X429499Y1748050D03*
X441499Y1758050D03*
X436799Y1772550D03*
X422999Y1778550D03*
X426499Y1855450D03*
X434299Y1876050D03*
Y1904050D03*
Y1895050D03*
X433299Y1922550D03*
Y1950550D03*
Y1941550D03*
X436299Y1977250D03*
X438999Y1987550D03*
X448499Y6050D03*
X445799Y165650D03*
Y184650D03*
X446799Y205650D03*
X449999Y217050D03*
X448999Y255550D03*
X444499Y283050D03*
X463999Y283550D03*
X443499Y354050D03*
X464499Y353050D03*
X458499Y382050D03*
X450300Y404200D03*
X453999Y417550D03*
X454999Y438550D03*
X454499Y472550D03*
Y458050D03*
Y490050D03*
X456499Y518050D03*
X453999Y509550D03*
X452499Y579550D03*
Y565050D03*
Y597050D03*
X463999Y659550D03*
X450399Y672750D03*
X444799Y687350D03*
X463999Y674050D03*
Y691550D03*
X451099Y711650D03*
X452099Y762450D03*
Y781450D03*
X453399Y807950D03*
Y826950D03*
X462999Y865050D03*
Y884050D03*
X464499Y896050D03*
X462499Y914550D03*
Y929050D03*
X443599Y945650D03*
X462499Y946550D03*
X461999Y966050D03*
Y985050D03*
X462499Y1043850D03*
Y1062850D03*
X463499Y1083850D03*
X463999Y1102050D03*
X444499Y1102550D03*
X454999Y1115550D03*
X453499Y1140550D03*
X454499Y1161550D03*
X443799Y1246250D03*
Y1274250D03*
Y1265250D03*
X448099Y1341250D03*
X444899Y1377950D03*
X464199Y1401450D03*
X459999Y1424050D03*
X456399Y1445950D03*
X459699Y1468050D03*
X445099Y1464250D03*
X444299Y1532650D03*
X461399Y1541650D03*
X452199Y1550650D03*
X449199Y1579050D03*
X443799Y1612250D03*
X460199Y1632850D03*
X449599Y1656950D03*
X448399Y1699450D03*
X447699Y1682850D03*
X458499Y1742050D03*
X463999Y1772050D03*
X445499Y1792550D03*
X448099Y1809450D03*
X443999Y1855950D03*
X460299Y1892350D03*
X446999Y1880050D03*
X460299Y1911350D03*
X446999Y1908050D03*
Y1899050D03*
X460299Y1920350D03*
X445999Y1926550D03*
X459299Y1938850D03*
X445999Y1954550D03*
Y1945550D03*
X459299Y1966850D03*
Y1957850D03*
X455799Y1976750D03*
X456500Y1987500D03*
X467999Y5550D03*
X485499Y6050D03*
X465799Y24750D03*
Y43750D03*
X466799Y64750D03*
X470399Y84550D03*
Y103550D03*
X471399Y124550D03*
X473099Y141050D03*
X483599Y179350D03*
X473099Y160050D03*
X474099Y181050D03*
X472999Y214550D03*
X469999Y254550D03*
X481499Y283550D03*
X466399Y304950D03*
X479299Y297250D03*
X483499Y353050D03*
X485000Y373200D03*
X484900Y394700D03*
X468799Y414250D03*
X472499Y458050D03*
X471499Y493950D03*
X485299Y534550D03*
X479999Y581050D03*
Y566550D03*
Y598550D03*
X472999Y736550D03*
X467699Y772750D03*
X468699Y788350D03*
X479599Y847550D03*
X475699Y880450D03*
X483499Y1064850D03*
X484499Y1085850D03*
X481499Y1102550D03*
X474499Y1115050D03*
X473099Y1144550D03*
X474099Y1165550D03*
X465499Y1265550D03*
Y1284550D03*
Y1293550D03*
X468999Y1323950D03*
X473999Y1342450D03*
X468699Y1362850D03*
X485599Y1367550D03*
X466699Y1378150D03*
X481499Y1402550D03*
Y1417050D03*
X482599Y1449950D03*
X478299Y1464850D03*
X466999Y1530650D03*
X474299Y1544750D03*
X472299Y1572050D03*
X484200Y1579900D03*
X465999Y1603450D03*
X472499Y1611550D03*
X484999Y1636550D03*
X472499Y1620550D03*
X483599Y1662550D03*
X467999Y1668050D03*
X485599Y1694850D03*
X467999Y1687050D03*
Y1696050D03*
X468499Y1712550D03*
X480999Y1756050D03*
X484999Y1779050D03*
X472699Y1792150D03*
X481299Y1811150D03*
X480499Y1855450D03*
X464999D03*
X476199Y1877450D03*
Y1905450D03*
Y1896450D03*
X475199Y1923950D03*
Y1951950D03*
Y1942950D03*
X473299Y1977250D03*
X476000Y1987000D03*
X498999Y6050D03*
X499999Y25550D03*
X500499Y47050D03*
X499999Y64050D03*
X500499Y79550D03*
Y94050D03*
Y108550D03*
Y126050D03*
X499999Y145550D03*
Y164550D03*
X504199Y193250D03*
X502899Y217150D03*
X488999Y254550D03*
X495999Y283550D03*
X502999Y353550D03*
X490999Y412550D03*
X503699Y419250D03*
X490999Y427050D03*
Y444550D03*
X498399Y470050D03*
X490499Y464050D03*
Y483050D03*
X491499Y504050D03*
X504499Y580550D03*
Y566050D03*
Y598050D03*
X488499Y659050D03*
Y673550D03*
Y691050D03*
X506599Y711650D03*
X487299Y716950D03*
X490299Y734550D03*
X489599Y752450D03*
X495999Y795050D03*
X493999Y813550D03*
Y828050D03*
Y845550D03*
X493499Y865050D03*
Y884050D03*
X485799Y920050D03*
Y901050D03*
X486799Y941050D03*
X493099Y996350D03*
X494099Y1017350D03*
X501499Y1102550D03*
X491999Y1115550D03*
X504399Y1132250D03*
X505399Y1153250D03*
X486499Y1210550D03*
Y1196050D03*
X506599Y1202350D03*
Y1216850D03*
X487099Y1218050D03*
X498299Y1323350D03*
X499199Y1350550D03*
X498899Y1386450D03*
Y1408350D03*
X500899Y1434350D03*
X505899Y1466250D03*
X488299Y1531050D03*
X499699Y1538950D03*
X502199Y1566250D03*
X487099Y1606250D03*
X501399Y1634550D03*
X502899Y1709650D03*
X496999Y1799550D03*
X499999Y1854950D03*
X505799Y1893050D03*
X492999Y1878050D03*
X505799Y1912050D03*
X493499Y1909050D03*
X492999Y1897050D03*
X505799Y1921050D03*
X491999Y1924550D03*
X504799Y1939550D03*
X492499Y1955550D03*
X491999Y1943550D03*
X504799Y1967550D03*
Y1958550D03*
X493799Y1977250D03*
X492500Y1987500D03*
X516499Y6550D03*
X522899Y45350D03*
Y64350D03*
X523899Y85350D03*
X520299Y122450D03*
Y141450D03*
X521299Y162450D03*
X508499Y255050D03*
X525999D03*
X515499Y284050D03*
X516899Y306950D03*
X520499Y353550D03*
X509999Y382550D03*
X518999Y416550D03*
X511299Y449150D03*
X519499Y471550D03*
Y489050D03*
X508699Y498950D03*
X518999Y508550D03*
X514499Y546050D03*
X509999Y640550D03*
Y655050D03*
Y672550D03*
X527499Y747150D03*
X525499Y772450D03*
X511199Y782050D03*
X512899Y823550D03*
X526499Y851150D03*
X512899Y842550D03*
X510899Y868150D03*
X522499Y876050D03*
X521999Y895550D03*
X506899Y919950D03*
Y900950D03*
X521999Y914550D03*
X516499Y957050D03*
X514499Y975550D03*
Y990050D03*
Y1007550D03*
X513999Y1046050D03*
Y1027050D03*
X518999Y1103050D03*
X511999Y1115550D03*
X527499Y1181550D03*
X527999Y1212550D03*
X527499Y1200550D03*
X507199Y1224350D03*
X525999Y1231050D03*
X507199Y1252350D03*
Y1243350D03*
X525999Y1245550D03*
X527499Y1278150D03*
X525999Y1263050D03*
X518499Y1346950D03*
X523499Y1360050D03*
X508599Y1370550D03*
X523499Y1379050D03*
X523999Y1391050D03*
X516999Y1418050D03*
Y1437050D03*
X517499Y1449050D03*
X518899Y1530150D03*
X510100Y1579800D03*
X508199Y1610450D03*
X518499Y1643950D03*
X509199Y1660550D03*
X507399Y1683350D03*
X522300Y1739200D03*
X508200Y1758200D03*
X515499Y1779050D03*
X526499Y1801150D03*
X514199Y1815750D03*
X517499Y1855450D03*
X519399Y1876750D03*
Y1904750D03*
Y1895750D03*
X518399Y1923250D03*
Y1951250D03*
Y1942250D03*
X509299Y1977250D03*
X511999Y1987550D03*
X535999Y6550D03*
X541499Y25050D03*
X541999Y46550D03*
X541499Y63550D03*
X541999Y79050D03*
Y93550D03*
Y108050D03*
Y125550D03*
X541499Y145050D03*
Y164050D03*
X528799Y199950D03*
X542499Y185050D03*
X533499Y217550D03*
X540499Y255050D03*
X536499Y283050D03*
X544799Y293950D03*
X540099Y306550D03*
X548100Y362200D03*
X530999Y381550D03*
X538799Y445050D03*
X539799Y466050D03*
X539299Y485550D03*
X535499Y545050D03*
X538999Y562050D03*
X534499Y640050D03*
Y654550D03*
Y672050D03*
X547999Y728550D03*
Y743050D03*
Y760550D03*
X547499Y780050D03*
X534499Y805950D03*
X547499Y799050D03*
X541399Y854450D03*
Y873450D03*
X539299Y935850D03*
X540299Y956850D03*
X540899Y981450D03*
Y1000450D03*
X541899Y1021450D03*
X534599Y1048550D03*
X535599Y1069550D03*
X538499Y1103050D03*
X548999Y1116050D03*
X529499D03*
X546499Y1180750D03*
Y1195250D03*
X547099Y1202750D03*
Y1230750D03*
Y1221750D03*
X548799Y1252850D03*
Y1267350D03*
X530499Y1297050D03*
X545099Y1355250D03*
X540399Y1382150D03*
X538799Y1409750D03*
X536799Y1436350D03*
X528499Y1460250D03*
X546099Y1467550D03*
X538999Y1528350D03*
X529799Y1555050D03*
X533800Y1575500D03*
X529499Y1616550D03*
X528999Y1604550D03*
X532499Y1635550D03*
X532599Y1655650D03*
X532499Y1669550D03*
Y1688550D03*
X532999Y1700550D03*
X538299Y1721050D03*
X532499Y1763050D03*
X539499Y1788150D03*
X544300Y1784638D03*
X531799Y1818450D03*
X538999Y1855950D03*
X547999Y1892350D03*
X533499Y1884050D03*
X547999Y1911350D03*
X533499Y1912050D03*
Y1903050D03*
X547999Y1920350D03*
X532499Y1930550D03*
X546999Y1938850D03*
X532499Y1949550D03*
X546999Y1966850D03*
Y1957850D03*
X546299Y1977250D03*
X528799Y1976750D03*
X532499Y1958550D03*
X531500Y1987500D03*
X551499Y6550D03*
X568099Y72550D03*
Y91550D03*
X569099Y112550D03*
X562799Y127750D03*
Y146750D03*
X563799Y167750D03*
X565999Y199950D03*
X568499Y217550D03*
X552999D03*
X557999Y322550D03*
Y326550D03*
X558099Y335050D03*
X557933Y331010D03*
X555999Y412550D03*
X556499Y467550D03*
Y485050D03*
X555999Y504550D03*
X558499Y562550D03*
Y616050D03*
X554304Y615840D03*
X554499Y624550D03*
X558699D03*
X554499Y620050D03*
X558709Y620245D03*
X565699Y710650D03*
X549999Y710050D03*
X562999Y898050D03*
X560999Y916550D03*
Y931050D03*
Y948550D03*
X560499Y968050D03*
Y987050D03*
X560999Y999050D03*
X558999Y1017550D03*
Y1032050D03*
X558499Y1069050D03*
X558999Y1049550D03*
X558499Y1088050D03*
X568499Y1101550D03*
X553999Y1103050D03*
X564499Y1116050D03*
X567999Y1187550D03*
Y1215550D03*
Y1206550D03*
X565999Y1234050D03*
Y1248550D03*
X566399Y1273850D03*
X549399Y1274850D03*
X561099Y1301050D03*
X549399Y1293850D03*
Y1302850D03*
X555699Y1322950D03*
X559099Y1343250D03*
X557499Y1424050D03*
Y1443050D03*
Y1452050D03*
X563499Y1486550D03*
Y1492050D03*
Y1497550D03*
Y1503550D03*
X567999Y1549950D03*
X552199Y1576650D03*
X552099Y1601950D03*
X569499Y1610550D03*
X553399Y1624550D03*
X569499Y1619550D03*
X554199Y1651950D03*
X555199Y1674750D03*
X555399Y1689350D03*
X555899Y1706750D03*
X556199Y1727050D03*
X560399Y1792550D03*
X555500Y1802700D03*
X554499Y1855950D03*
X562599Y1893450D03*
Y1874450D03*
Y1902450D03*
X561599Y1920950D03*
Y1948950D03*
Y1939950D03*
X570299Y1976250D03*
X568999Y1987050D03*
X553499D03*
X570999Y6050D03*
X588499Y6550D03*
X587999Y25050D03*
X588499Y46550D03*
X587999Y63550D03*
X588499Y125550D03*
X587999Y145050D03*
Y164050D03*
X588999Y185050D03*
X587999Y217050D03*
X572999Y255050D03*
Y269550D03*
Y287050D03*
X572499Y306550D03*
Y325550D03*
X573499Y346550D03*
X579899Y375750D03*
X577399Y420050D03*
X578399Y441050D03*
X577899Y460550D03*
X576099Y481850D03*
X577099Y502850D03*
X576599Y522350D03*
X579499Y561550D03*
X573499Y658550D03*
Y673050D03*
Y690550D03*
X586299Y711250D03*
X577999Y732050D03*
X575999Y750550D03*
Y765050D03*
Y782550D03*
X575499Y802050D03*
Y821050D03*
X576499Y842050D03*
X578299Y895650D03*
Y914650D03*
X583299Y961450D03*
X570899Y946850D03*
X583299Y980450D03*
X570899Y965850D03*
X571899Y986850D03*
X573499Y1036550D03*
Y1055550D03*
X574499Y1076550D03*
X588499Y1101550D03*
X578999Y1114550D03*
X582699Y1233250D03*
X583299Y1255250D03*
X582699Y1247750D03*
X583299Y1274250D03*
X579299Y1300750D03*
X583299Y1283250D03*
X581999Y1370150D03*
X580999Y1412750D03*
X575699Y1438950D03*
X582999Y1461250D03*
X590599Y1483450D03*
X582299Y1534150D03*
X588099Y1572050D03*
X573400Y1577600D03*
X588000Y1604000D03*
X590799Y1627850D03*
X580799Y1646150D03*
X572999Y1675550D03*
X590599Y1694450D03*
X572999Y1694550D03*
Y1703550D03*
X580299Y1722550D03*
X582599Y1740050D03*
X573999Y1855450D03*
X588899Y1882350D03*
X575999Y1888050D03*
X588899Y1910350D03*
Y1901350D03*
X575999Y1907050D03*
X587899Y1928850D03*
X576499Y1919050D03*
X574999Y1934550D03*
X587899Y1956850D03*
Y1947850D03*
X574999Y1953550D03*
X585799Y1976250D03*
X575499Y1965550D03*
X588499Y1986550D03*
X608499Y6550D03*
X603999Y35350D03*
Y54350D03*
X604999Y75350D03*
X603999Y133750D03*
Y152750D03*
X604999Y173750D03*
X605499Y217550D03*
X599299Y344650D03*
X600299Y365650D03*
X599799Y385150D03*
X607399Y380250D03*
X592999Y407550D03*
Y422050D03*
Y439550D03*
X592499Y459050D03*
Y478050D03*
X593499Y499050D03*
X606499Y584550D03*
X595999Y624050D03*
Y609550D03*
Y641550D03*
X605299Y661750D03*
X609499Y708050D03*
X597999Y690050D03*
X607499Y726550D03*
Y741050D03*
Y758550D03*
X606999Y778050D03*
Y797050D03*
X603499Y904050D03*
X601499Y922550D03*
Y937050D03*
Y954550D03*
X600999Y1002050D03*
X611399Y1026650D03*
X598999Y1020550D03*
X611399Y1045650D03*
X598999Y1035050D03*
X612399Y1066650D03*
X598999Y1052550D03*
X598499Y1072050D03*
X605999Y1102050D03*
X598499Y1091050D03*
X598999Y1114550D03*
X603899Y1157850D03*
X597599Y1196050D03*
X596599Y1215050D03*
X600899Y1238650D03*
X598499Y1280550D03*
Y1261550D03*
X598999Y1292550D03*
X608899Y1305050D03*
X605599Y1326350D03*
X606199Y1338250D03*
X599499Y1351550D03*
X599999Y1382550D03*
X599499Y1370550D03*
X604899Y1407750D03*
X601299Y1447650D03*
X610899Y1496750D03*
X599799Y1544650D03*
X611900Y1577900D03*
X612499Y1615550D03*
X611999Y1603550D03*
X600599Y1645450D03*
X593399Y1668850D03*
X609499Y1675050D03*
Y1692050D03*
X607599Y1716450D03*
X606999Y1745550D03*
X593299Y1760950D03*
X608599Y1810750D03*
X595199Y1820910D03*
X611999Y1855950D03*
X591499D03*
X602799Y1887350D03*
Y1906350D03*
X601799Y1933850D03*
X602799Y1915350D03*
X601799Y1952850D03*
Y1961850D03*
X605299Y1975750D03*
X605999Y1987050D03*
X625999Y7050D03*
X624499Y23050D03*
X624999Y44550D03*
X624499Y61550D03*
X624999Y123550D03*
X624499Y143050D03*
Y162050D03*
X625499Y183050D03*
X623899Y202550D03*
X625499Y217550D03*
X627999Y262550D03*
Y248050D03*
Y280050D03*
X627499Y299550D03*
X628200Y320000D03*
X628499Y339550D03*
X632399Y358750D03*
X620999Y411550D03*
X621999Y432550D03*
X621499Y452050D03*
Y466550D03*
Y484050D03*
X613700Y504600D03*
X625999Y585050D03*
X620499Y623550D03*
Y609050D03*
X631999Y639650D03*
X622999Y672050D03*
Y689550D03*
X629099Y714050D03*
X633499Y750150D03*
X621499Y767150D03*
X621999Y835050D03*
X612999Y854550D03*
X629499Y853050D03*
Y868550D03*
X613499Y868050D03*
X616699Y948250D03*
Y967250D03*
X617699Y988250D03*
X631999Y1001550D03*
X629999Y1020050D03*
Y1034550D03*
Y1052050D03*
X629499Y1071550D03*
Y1090550D03*
X616499Y1115050D03*
X627699Y1143550D03*
X628699Y1164550D03*
X626199Y1183450D03*
X630499Y1243950D03*
X617599Y1246250D03*
X618199Y1268250D03*
X617599Y1260750D03*
X618199Y1296250D03*
Y1287250D03*
X631799Y1322650D03*
X617899Y1360850D03*
X632499Y1347950D03*
X625499Y1383450D03*
X627499Y1406050D03*
X626799Y1432350D03*
X625199Y1489150D03*
X617699Y1530350D03*
X623499Y1564050D03*
X633499Y1615450D03*
X628499Y1636650D03*
X627299Y1659550D03*
X625499Y1725050D03*
X619499Y1803150D03*
X627273Y1793905D03*
X626999Y1800050D03*
X632799Y1820450D03*
X627494Y1829068D03*
X627499Y1855950D03*
X630699Y1872750D03*
Y1891750D03*
Y1900750D03*
X616499Y1913050D03*
Y1894050D03*
X629699Y1919250D03*
X616499Y1922050D03*
X629699Y1947250D03*
Y1938250D03*
X615499Y1940550D03*
X622799Y1976250D03*
X615499Y1959550D03*
Y1968550D03*
X626999Y1987050D03*
X645499Y7050D03*
X651799Y40650D03*
Y59650D03*
X652799Y80650D03*
X649899Y138350D03*
Y157350D03*
X650899Y178350D03*
X642999Y218050D03*
X653999Y286550D03*
X635399Y376250D03*
X643599Y395950D03*
X644599Y416950D03*
X644099Y450950D03*
Y436450D03*
X642499Y525750D03*
X643499Y546750D03*
X642999Y566250D03*
X646999Y584550D03*
X640599Y604650D03*
X645099Y639150D03*
X647499Y657050D03*
Y671550D03*
X648999Y702350D03*
X647499Y689050D03*
X651999Y718350D03*
X647399Y742150D03*
X653099Y803350D03*
X645799Y816650D03*
X641599Y843250D03*
Y862250D03*
X642599Y883250D03*
X639499Y952150D03*
Y971150D03*
X633999Y1103050D03*
X641799Y1137650D03*
X650299Y1153150D03*
X651299Y1174150D03*
X650599Y1182050D03*
X651599Y1203050D03*
X638999Y1267550D03*
Y1286550D03*
Y1295550D03*
X654499Y1354050D03*
Y1373050D03*
X652999Y1403550D03*
Y1418050D03*
Y1435550D03*
X636799Y1461250D03*
X643099Y1541350D03*
X652399Y1575850D03*
X639200Y1576200D03*
X635500Y1603900D03*
X652499Y1618550D03*
Y1609550D03*
X649399Y1644950D03*
X635099Y1691150D03*
X642499Y1709050D03*
X650399Y1771250D03*
X642400Y1800100D03*
X633837Y1807384D03*
X640999Y1815550D03*
X644049Y1810834D03*
X645099Y1877550D03*
X645399Y1906150D03*
X646799Y1926450D03*
X644999Y1934050D03*
Y1953050D03*
X643799Y1976250D03*
X645499Y1965050D03*
X642499Y1987050D03*
X660999Y7050D03*
X674999Y20550D03*
X675499Y42050D03*
Y74550D03*
X674999Y59050D03*
X675499Y89050D03*
Y103550D03*
Y121050D03*
X674999Y140550D03*
Y159550D03*
X675999Y180550D03*
X662499Y218050D03*
X656499Y307050D03*
Y324550D03*
X655999Y344050D03*
X659899Y363250D03*
X666999Y476550D03*
Y491050D03*
Y508550D03*
X666499Y528050D03*
Y547050D03*
X667499Y568050D03*
X674999Y601550D03*
X665999Y623550D03*
X673999Y645150D03*
X665499Y766550D03*
X664999Y786050D03*
Y805050D03*
X665999Y826050D03*
X663999Y844550D03*
Y876550D03*
Y859050D03*
X663499Y896050D03*
Y915050D03*
X664499Y936050D03*
X658999Y959050D03*
X656999Y977550D03*
Y992050D03*
X673999Y1017550D03*
X656999Y1009550D03*
X673999Y1036550D03*
X656499Y1029050D03*
X674699Y1061450D03*
X656499Y1048050D03*
X674699Y1080450D03*
X669499Y1116550D03*
X674999Y1134950D03*
X667199Y1152850D03*
X668199Y1173850D03*
X670199Y1192750D03*
X671199Y1213750D03*
X668699Y1227650D03*
X657099Y1272850D03*
X657799Y1288450D03*
X672999Y1303450D03*
X656399Y1307050D03*
X671999Y1324950D03*
X665699Y1337250D03*
X654999Y1385050D03*
X659699Y1445950D03*
X665699Y1462250D03*
X656099Y1479550D03*
X672399Y1508750D03*
X673699Y1535350D03*
X662099Y1549650D03*
X670699Y1603150D03*
X671399Y1625350D03*
X657099Y1668850D03*
X674999Y1676550D03*
X656499Y1697050D03*
X675499Y1738050D03*
X665399Y1752350D03*
X675499Y1757050D03*
X675999Y1769050D03*
X659159Y1792278D03*
X659549Y1815384D03*
X667999Y1870950D03*
X669399Y1855350D03*
X674899Y1892350D03*
X661299Y1890050D03*
X674899Y1911350D03*
X661299Y1909050D03*
X674899Y1920350D03*
X661299Y1918050D03*
X673899Y1938850D03*
X660299Y1936550D03*
Y1955550D03*
X673899Y1966850D03*
Y1957850D03*
X660299Y1964550D03*
X659299Y1976250D03*
X661999Y1986550D03*
X680499Y6550D03*
X694999Y62650D03*
Y81650D03*
X695999Y102650D03*
X688999Y196550D03*
X677999Y218050D03*
X683499Y263050D03*
Y248550D03*
X680500Y280700D03*
X682999Y300050D03*
Y319050D03*
X683999Y340050D03*
X694999Y480550D03*
X695999Y501550D03*
X695499Y521050D03*
X691399Y548350D03*
X692399Y569350D03*
X691899Y588850D03*
X690499Y623050D03*
X693999Y648150D03*
X678499Y671050D03*
X679299Y703050D03*
X678499Y688550D03*
X681899Y713650D03*
X696299Y741850D03*
X694599Y763450D03*
X685999Y780050D03*
X687099Y804650D03*
Y823650D03*
X688099Y844650D03*
X687099Y896350D03*
Y915350D03*
X688099Y936350D03*
X678299Y978350D03*
Y997350D03*
X694999Y993050D03*
X692999Y1011550D03*
Y1026050D03*
Y1043550D03*
X692499Y1063050D03*
Y1082050D03*
X689999Y1105550D03*
X695999Y1203050D03*
Y1235050D03*
Y1217550D03*
X684299Y1249550D03*
X695999Y1323350D03*
X677999Y1347550D03*
X694999Y1360050D03*
X680299Y1365850D03*
X694999Y1379050D03*
X681299Y1393150D03*
X692999Y1406550D03*
X694999Y1388050D03*
X678299Y1425050D03*
X692999Y1421050D03*
X686999Y1468850D03*
X685299Y1551950D03*
X681299Y1579150D03*
X693599Y1602450D03*
X686699Y1638650D03*
X691999Y1660550D03*
X693099Y1722350D03*
X690499Y1744950D03*
X694599Y1768450D03*
X693549Y1793134D03*
X686473Y1818375D03*
X686999Y1870250D03*
X690899Y1855850D03*
X696299Y1898850D03*
X676399Y1901150D03*
X695299Y1926450D03*
X685499Y1940050D03*
X696299Y1976250D03*
X678799Y1975750D03*
X685499Y1959050D03*
Y1968050D03*
X679499Y1987050D03*
X697999Y7050D03*
X712499Y6050D03*
X699699Y141750D03*
Y160750D03*
X700699Y181750D03*
X711999Y218050D03*
X711499Y252550D03*
X711999Y307550D03*
Y293050D03*
Y325050D03*
X711499Y344550D03*
X712699Y434450D03*
X713699Y455450D03*
X713199Y474950D03*
Y489450D03*
X712599Y521050D03*
X713599Y542050D03*
X713099Y561550D03*
X699999Y610050D03*
X717099Y636050D03*
X702999Y656050D03*
Y688050D03*
Y670550D03*
X710899Y751150D03*
X716599Y736850D03*
X706999Y792550D03*
X707499Y773050D03*
X706999Y811550D03*
X707999Y832550D03*
X705999Y851050D03*
Y865550D03*
X707399Y899550D03*
Y918550D03*
X706499Y942550D03*
X713999Y1017050D03*
Y1031550D03*
X713499Y1068550D03*
X713999Y1049050D03*
X709999Y1105550D03*
X700499Y1118550D03*
X704299Y1132650D03*
X716999Y1148150D03*
X697499Y1153550D03*
X717999Y1169150D03*
X697499Y1172550D03*
X713399Y1178750D03*
X697999Y1184550D03*
X713599Y1214650D03*
X714399Y1199750D03*
X708699Y1243550D03*
X709699Y1264550D03*
X707899Y1346250D03*
X702299Y1404450D03*
X713899Y1386450D03*
X716899Y1459850D03*
X700899Y1450250D03*
X716199Y1503050D03*
X714599Y1533950D03*
X708899Y1549250D03*
X698599Y1568550D03*
X706700Y1579900D03*
X717099Y1702450D03*
X702599Y1730550D03*
X715999Y1744050D03*
X709099Y1751850D03*
X715999Y1763050D03*
Y1772050D03*
X706549Y1793634D03*
X717000Y1812384D03*
X705000Y1811900D03*
X711500Y1817700D03*
X704300Y1828400D03*
X697999Y1844550D03*
X706399Y1855850D03*
X705599Y1891850D03*
X716599Y1918450D03*
X698299Y1948050D03*
X711899Y1944050D03*
X709199Y1962950D03*
X717999Y1987550D03*
X702499D03*
X729999Y6550D03*
X725499Y23550D03*
X725999Y45050D03*
X725499Y62050D03*
X725999Y77550D03*
Y92050D03*
Y106550D03*
X738199Y137450D03*
X725999Y124050D03*
X725499Y143550D03*
Y162550D03*
X726499Y183550D03*
X728899Y204550D03*
X729499Y218550D03*
X723200Y275500D03*
X737999Y467050D03*
X738999Y488050D03*
X738499Y507550D03*
Y539550D03*
Y522050D03*
X737999Y559050D03*
X731499Y572050D03*
Y586550D03*
Y604050D03*
X721499Y617550D03*
X729699Y640350D03*
X723499Y654850D03*
X739399Y688150D03*
X720899Y712250D03*
X732499Y729250D03*
X727099Y715050D03*
X733799Y761450D03*
X723999Y783350D03*
Y802350D03*
X724999Y823350D03*
X728499Y841850D03*
X729999Y862850D03*
Y881850D03*
X730999Y902850D03*
X723699Y936250D03*
Y955250D03*
X724699Y976250D03*
X734999Y1030550D03*
Y1045050D03*
Y1062550D03*
X727499Y1106050D03*
X737999Y1119050D03*
X720499Y1118550D03*
X727499Y1132650D03*
X737999Y1159550D03*
Y1187550D03*
Y1178550D03*
X735999Y1206050D03*
X725499Y1231650D03*
X735999Y1220550D03*
X725499Y1250650D03*
X723499Y1278150D03*
X725499Y1259650D03*
X723499Y1292650D03*
X719199Y1322350D03*
X739199Y1348950D03*
X734199Y1373850D03*
X736199Y1399050D03*
X737799Y1428350D03*
X721899Y1419050D03*
X719499Y1446650D03*
X729199Y1492750D03*
X735799Y1533650D03*
X734499Y1563550D03*
X722199Y1564250D03*
X719999Y1605050D03*
X732999Y1620050D03*
X738799Y1677250D03*
X727399Y1694350D03*
X739199Y1716750D03*
X721199Y1723750D03*
X729999Y1756450D03*
X729499Y1778750D03*
X728099Y1844750D03*
X723199Y1867950D03*
X725899Y1855350D03*
X732999Y1868550D03*
X728299Y1888850D03*
X732199Y1878750D03*
X728799Y1908150D03*
Y1933050D03*
X736799Y1919450D03*
X730499Y1954650D03*
X721499Y1974550D03*
X737499Y1987050D03*
X749499Y6550D03*
X751499Y48350D03*
X757499Y44050D03*
Y63050D03*
X758499Y84050D03*
X752099Y112150D03*
X757999Y154550D03*
Y159050D03*
X753999Y154550D03*
Y159050D03*
X749499Y218550D03*
X755499Y314550D03*
X755346Y319149D03*
X751539Y313984D03*
X751499Y318050D03*
X749899Y398550D03*
X750899Y419550D03*
X750399Y453550D03*
Y439050D03*
X755199Y488150D03*
X756199Y509150D03*
X755699Y528650D03*
X754499Y564650D03*
X755499Y585650D03*
X754999Y605150D03*
X744999Y626550D03*
X751499Y679148D03*
X757400Y686300D03*
X747999Y670750D03*
X754999Y694050D03*
X749999Y700050D03*
X749499Y716050D03*
X744999Y715550D03*
X749999Y720050D03*
X745499D03*
X749799Y767450D03*
X743099Y785350D03*
X751999Y817050D03*
X751499Y855550D03*
Y836550D03*
X751599Y887350D03*
Y906350D03*
X752599Y927350D03*
X749999Y946550D03*
Y965550D03*
X751399Y1004550D03*
X750999Y986550D03*
X751399Y1023550D03*
X752399Y1052550D03*
X753999Y1100050D03*
X755499Y1119050D03*
X749999Y1119550D03*
X748999Y1115550D03*
X748499Y1111550D03*
X758799Y1171150D03*
Y1190150D03*
Y1199150D03*
X756799Y1232150D03*
Y1217650D03*
X757399Y1258650D03*
Y1239650D03*
X740499Y1252550D03*
X757399Y1267650D03*
X740499Y1270050D03*
X740799Y1298750D03*
X755399Y1300650D03*
Y1286150D03*
X742099Y1320650D03*
X754999Y1420050D03*
Y1437550D03*
X741099Y1450250D03*
Y1498150D03*
X747199Y1509150D03*
X755499Y1507550D03*
X751000Y1517000D03*
X757500Y1522500D03*
X751000Y1521000D03*
Y1525000D03*
X755499Y1568550D03*
X743400Y1578700D03*
X751300Y1604900D03*
X756299Y1679050D03*
X750099Y1694950D03*
X756499Y1712150D03*
X747499Y1734350D03*
X756900Y1766000D03*
X752900D03*
X751899Y1752150D03*
X747799Y1766750D03*
X751999Y1775550D03*
X756617Y1780067D03*
X752657Y1779496D03*
X755999Y1775550D03*
X753558Y1769946D03*
X757518Y1770517D03*
X744049Y1791634D03*
X740549Y1802634D03*
X753949Y1798194D03*
X740549Y1810384D03*
X747599Y1844250D03*
X744699Y1868450D03*
X758399Y1868350D03*
X743399Y1855850D03*
X743799Y1888850D03*
X753699Y1879250D03*
X755299Y1902150D03*
X739799D03*
X755500Y1914500D03*
X746499Y1974250D03*
X754999Y1987550D03*
X764999Y6550D03*
X763399Y24150D03*
X774399Y54050D03*
X775399Y80250D03*
X778399Y105250D03*
X767399Y140150D03*
X760799Y181950D03*
X779399Y200550D03*
X766999Y219050D03*
X781478Y363924D03*
X776978D03*
X772478Y359924D03*
Y363924D03*
X774999Y476550D03*
Y462050D03*
Y494050D03*
X774499Y513550D03*
Y532550D03*
X775499Y553550D03*
X777499Y638050D03*
X764599Y655750D03*
X777499Y664550D03*
X771800Y686600D03*
X766499Y699050D03*
Y705550D03*
X771196Y764382D03*
Y760382D03*
X775696Y764382D03*
X780196D03*
X778999Y806950D03*
X763099Y796350D03*
X775199Y839250D03*
Y858250D03*
X776199Y879250D03*
X772199Y920650D03*
Y939650D03*
X773199Y960650D03*
X776899Y988050D03*
Y1007050D03*
X777899Y1028050D03*
X760999Y1095550D03*
X773499Y1101050D03*
X769499D03*
X773499Y1105050D03*
X769499D03*
X780333Y1165892D03*
X775833D03*
X771333Y1161892D03*
Y1165892D03*
X762499Y1335550D03*
X779399Y1361850D03*
X762499Y1353050D03*
X773999Y1393450D03*
X763399Y1401450D03*
X769300Y1488100D03*
X779000Y1488400D03*
X771399Y1474550D03*
X770999Y1500050D03*
X780499D03*
X773499Y1509050D03*
X769499D03*
X778327Y1569796D03*
X773327Y1565796D03*
X773827Y1569796D03*
X768500Y1577500D03*
X776999Y1647650D03*
X765099Y1664950D03*
X770399Y1699650D03*
X779999Y1717050D03*
X770099Y1730350D03*
X779899Y1748150D03*
X765600Y1756800D03*
X767159Y1792364D03*
X765099Y1844750D03*
X779699Y1867950D03*
X779399Y1855850D03*
X763899D03*
X780799Y1888850D03*
X763299Y1888350D03*
X769199Y1879250D03*
X774499Y1908050D03*
X765999D03*
X773999Y1923550D03*
X767999Y1923050D03*
X774499Y1930050D03*
X768999D03*
X775999Y1916050D03*
X768499Y1917550D03*
X775814Y1975699D03*
X770814Y1971713D03*
X771814Y1975713D03*
X777499Y1987550D03*
X784499Y6050D03*
X801999Y6550D03*
X796999Y27050D03*
X797499Y48550D03*
X796999Y65550D03*
X797499Y81050D03*
Y95550D03*
Y110050D03*
X796599Y123450D03*
X797499Y127550D03*
X796999Y147050D03*
Y166050D03*
X797999Y187050D03*
X786499Y219050D03*
X800999Y216550D03*
X796873Y307571D03*
Y303071D03*
Y298571D03*
Y294071D03*
X784478Y355424D03*
Y359924D03*
X789999Y570050D03*
Y602050D03*
Y584550D03*
X785499Y641050D03*
X794999Y664550D03*
X786500Y686100D03*
X798000Y686400D03*
X782999Y699550D03*
X794331Y698353D03*
Y702853D03*
Y707353D03*
Y711853D03*
X799385Y761436D03*
X783196Y760382D03*
Y755882D03*
X802499Y814550D03*
X801999Y834050D03*
Y853050D03*
X800999Y892550D03*
Y907050D03*
Y924550D03*
X800499Y944050D03*
Y963050D03*
X801499Y984050D03*
X800999Y1005550D03*
Y1020050D03*
Y1037550D03*
X783999Y1096550D03*
X789499Y1099550D03*
X802499Y1097566D03*
X798499D03*
X783333Y1157392D03*
Y1161892D03*
X790999Y1194550D03*
Y1175550D03*
X791499Y1206550D03*
X789499Y1225050D03*
Y1257050D03*
Y1239550D03*
X788999Y1278150D03*
X791999Y1294450D03*
X795299Y1326650D03*
X799999Y1340550D03*
X798299Y1344250D03*
X799999Y1358050D03*
X781999Y1434650D03*
X786500Y1488600D03*
X801300Y1489000D03*
X786999Y1506550D03*
X795999Y1509550D03*
Y1504550D03*
Y1518550D03*
Y1514050D03*
X785827Y1561296D03*
Y1565796D03*
X782827Y1569796D03*
X797299Y1646650D03*
X802899Y1670550D03*
X782999Y1668050D03*
Y1687050D03*
X783499Y1699050D03*
X794499Y1734550D03*
X787900Y1758800D03*
X801099Y1844750D03*
X785599D03*
X791799Y1855850D03*
X797199Y1868450D03*
X788699Y1878750D03*
X783499Y1907050D03*
X790499Y1913050D03*
X795526Y1909696D03*
X795493Y1913696D03*
X795501Y1917696D03*
X795499Y1922050D03*
X783814Y1967213D03*
Y1971713D03*
X784016Y1975708D03*
X789299Y1983850D03*
X792999Y1987550D03*
X818999Y6050D03*
X817599Y43750D03*
X813299Y49350D03*
Y68350D03*
X814299Y89350D03*
X813299Y110850D03*
X821199Y137450D03*
X805899Y126150D03*
X809373Y307571D03*
Y297571D03*
Y292571D03*
X808999Y303050D03*
X821499Y314050D03*
X819299Y413250D03*
Y394250D03*
X820299Y434250D03*
X802999Y466050D03*
X803999Y487050D03*
X803499Y506550D03*
Y538550D03*
Y521050D03*
X802999Y558050D03*
X814499Y569550D03*
Y601550D03*
Y584050D03*
X809700Y686300D03*
X806300Y670600D03*
X806831Y701853D03*
Y706853D03*
X806999Y697050D03*
X806831Y711853D03*
X811499Y767550D03*
Y782050D03*
Y799550D03*
X802999Y874050D03*
X811499Y1097050D03*
X807499D03*
X807341Y1111216D03*
Y1101216D03*
X806999Y1106050D03*
X807341Y1116216D03*
X808299Y1175850D03*
X806599Y1189750D03*
X803599Y1211050D03*
X810199Y1229350D03*
Y1248350D03*
Y1257350D03*
X808199Y1275850D03*
Y1290350D03*
X822199Y1335250D03*
X819199Y1353550D03*
X806499Y1390550D03*
X803299Y1426650D03*
X806499Y1408050D03*
X805899Y1464250D03*
X809245Y1508722D03*
Y1503722D03*
Y1518722D03*
X808999Y1513550D03*
X813300Y1604100D03*
X803599Y1618350D03*
X814599Y1642650D03*
X823499Y1674050D03*
X808899Y1698450D03*
X823499Y1693050D03*
Y1702050D03*
X824100Y1719900D03*
X819400Y1721900D03*
X819200Y1727100D03*
X808299Y1755250D03*
X809299Y1856350D03*
X818900Y1870800D03*
X806199Y1879250D03*
X807936Y1914865D03*
Y1910365D03*
X807997Y1922865D03*
X808005Y1918865D03*
X813599Y1979950D03*
X812499Y1987050D03*
X836499Y6550D03*
X824899Y25150D03*
X844799Y19850D03*
X839999Y46050D03*
X840499Y55050D03*
X840999Y62550D03*
X841499Y71550D03*
X843499Y82550D03*
X838999Y85050D03*
X837999Y91050D03*
X838499Y107050D03*
Y99550D03*
X839499Y119050D03*
X837499Y138550D03*
X838499Y145050D03*
X838999Y313550D03*
X838499Y352050D03*
X839299Y390950D03*
Y409950D03*
X840299Y430950D03*
X824899Y500450D03*
X825899Y521450D03*
X825399Y540950D03*
X834599Y543050D03*
X835599Y564050D03*
X835099Y583550D03*
X841000Y671100D03*
X836149Y714050D03*
X835999Y767050D03*
X837799Y754150D03*
X835999Y781550D03*
Y799050D03*
X825199Y850850D03*
X827699Y873450D03*
Y892450D03*
X828699Y913450D03*
X826999Y963150D03*
Y982150D03*
X827999Y1003150D03*
X841999Y1118550D03*
X836149D03*
X839999Y1157550D03*
X831499Y1181550D03*
Y1209550D03*
Y1200550D03*
X829499Y1228050D03*
Y1242550D03*
X828199Y1267850D03*
X826199Y1294450D03*
X831499Y1324950D03*
X841999Y1341050D03*
Y1358550D03*
X825500Y1379000D03*
X834499Y1397550D03*
X836600Y1416500D03*
X843999Y1523550D03*
X839499D03*
X839899Y1562050D03*
X825999Y1578050D03*
X826499Y1609050D03*
X827199Y1622750D03*
X841499Y1638950D03*
X837199Y1660550D03*
X839199Y1683550D03*
X842799Y1701150D03*
X829200Y1719800D03*
X844499Y1788050D03*
X842500Y1799000D03*
X827999Y1791550D03*
X829799Y1856350D03*
X833199Y1868450D03*
X842199Y1879250D03*
X833100Y1878500D03*
X843999Y1928550D03*
X838999D03*
X840999Y1970550D03*
X829499Y1980250D03*
X829999Y1987550D03*
X855999Y6550D03*
X860799Y24150D03*
X865499Y39550D03*
X854499D03*
X856499Y71050D03*
X855499Y82050D03*
X845999Y111050D03*
X853999Y132550D03*
X865499Y125550D03*
X849999Y145550D03*
X863999Y313550D03*
X858400Y352300D03*
X847999Y352550D03*
X854499Y387550D03*
Y373050D03*
Y405050D03*
X853999Y424550D03*
Y443550D03*
X854999Y464550D03*
X860199Y525050D03*
X861199Y546050D03*
X860699Y565550D03*
X861800Y591200D03*
X860499Y607550D03*
X860796Y678632D03*
X859999Y713050D03*
Y767550D03*
X856299Y753150D03*
X846799Y754150D03*
X865000Y752100D03*
X859999Y782050D03*
Y799550D03*
X847799Y828250D03*
X857099Y873450D03*
X866199Y920350D03*
Y901350D03*
X850999Y962550D03*
Y943550D03*
X851999Y983550D03*
X859999Y1118550D03*
X846499Y1170450D03*
X856400Y1157700D03*
X848999Y1158050D03*
X863300Y1153800D03*
X845799Y1190450D03*
X849799Y1199750D03*
X851999Y1237550D03*
Y1218550D03*
X852499Y1249550D03*
X850499Y1268050D03*
X860099Y1295450D03*
X850499Y1300050D03*
Y1282550D03*
X861999Y1522550D03*
X850099Y1572250D03*
X858400Y1561900D03*
X850499Y1562050D03*
X865300Y1557700D03*
X864000Y1578200D03*
X849900Y1605100D03*
X852499Y1621350D03*
X855799Y1658250D03*
X855350Y1703201D03*
X864099Y1683550D03*
X853799Y1790850D03*
X863099Y1813150D03*
X862499Y1823550D03*
X854977Y1818994D03*
X861414Y1928550D03*
X864414Y1940050D03*
X850499Y1977950D03*
X856999Y1970050D03*
X849999Y1970550D03*
X865200Y1968000D03*
X864999Y1987050D03*
X849499D03*
X871499Y6550D03*
X885999Y21150D03*
X883999Y39050D03*
X881499Y70550D03*
X866999D03*
X876999Y82050D03*
X867499D03*
X886499Y99550D03*
Y104550D03*
X872499Y133050D03*
X875499Y125550D03*
X871499Y146050D03*
X871786Y218924D03*
Y203924D03*
X887400Y233555D03*
X871786Y233924D03*
X887400Y259700D03*
X879878Y247724D03*
X870600Y346700D03*
X875799Y386250D03*
Y405250D03*
X876799Y426250D03*
X884399Y443450D03*
Y462450D03*
X885399Y483450D03*
X870719Y609705D03*
X870773Y624705D03*
X870719Y639705D03*
X887401Y665000D03*
X881125Y652050D03*
X871786Y679436D03*
Y709482D03*
X871499Y689436D03*
X866499Y724550D03*
X871385Y719436D03*
X884499Y767050D03*
Y781550D03*
Y799050D03*
X873999Y830550D03*
Y845050D03*
Y862550D03*
X886999Y907350D03*
X867199Y941350D03*
X886999Y947250D03*
X870777Y1014948D03*
X870468Y1030227D03*
X886919Y1044478D03*
X870298Y1045227D03*
X880033Y1058592D03*
X887400Y1070600D03*
X871399Y1182850D03*
Y1201850D03*
Y1210850D03*
X869399Y1229350D03*
Y1243850D03*
X872099Y1268150D03*
X871399Y1291450D03*
X875399Y1322650D03*
X873499Y1356050D03*
X868499Y1392550D03*
Y1410050D03*
X871836Y1420460D03*
X886913Y1449010D03*
X871836Y1435460D03*
X879727Y1463696D03*
X871836Y1450460D03*
X887499Y1476050D03*
X873099Y1572550D03*
X886900Y1604100D03*
X866499Y1603050D03*
Y1612050D03*
X868099Y1635650D03*
X887299Y1620050D03*
X877699Y1646650D03*
X882999Y1678250D03*
X879200Y1698700D03*
X879900Y1709300D03*
X883900Y1709500D03*
X875900D03*
X882700Y1738300D03*
X886900Y1737900D03*
X872950Y1744401D03*
X866699Y1770950D03*
X879399Y1798150D03*
X869634Y1826876D03*
X871836Y1840972D03*
X887499Y1855550D03*
X869999Y1855972D03*
X887401Y1881500D03*
X879399Y1974550D03*
X873399Y1963650D03*
X868699Y1983250D03*
X884499Y1986550D03*
X890999Y6050D03*
X908499Y6550D03*
X902999Y22050D03*
X902499Y35050D03*
X905499Y56550D03*
X904999Y61550D03*
X904499Y74050D03*
X904999Y67550D03*
X890459Y100116D03*
X890499Y104550D03*
X889999Y132550D03*
X891999Y146050D03*
X906999Y243150D03*
Y224150D03*
X907999Y264150D03*
X906399Y295250D03*
Y314250D03*
X907399Y335250D03*
X904999Y370550D03*
Y385050D03*
Y402550D03*
X904499Y422050D03*
Y441050D03*
X905499Y462050D03*
X903999Y574378D03*
X898999Y622050D03*
Y604550D03*
X894000Y642400D03*
X900999Y652550D03*
Y670050D03*
X895999Y702550D03*
Y720050D03*
X898499Y830050D03*
Y844550D03*
X889699Y876050D03*
X898499Y862050D03*
X897299Y1182450D03*
X887999Y1209350D03*
X892499Y1224550D03*
Y1252550D03*
Y1243550D03*
X890499Y1271050D03*
Y1285550D03*
X890999Y1336550D03*
Y1354050D03*
X894499Y1423550D03*
Y1441050D03*
X895499Y1488050D03*
X902759Y1509585D03*
X894499Y1522050D03*
Y1539550D03*
X907500Y1604000D03*
X895999Y1661250D03*
X903599Y1686850D03*
X893200Y1721300D03*
X902900Y1709800D03*
X893200Y1730000D03*
X904814Y1789113D03*
X903299Y1814750D03*
X894999Y1829050D03*
X905299Y1852650D03*
X894000Y1868452D03*
X900299Y1876950D03*
X897299Y1904150D03*
X907599Y1930050D03*
X897599Y1938750D03*
X904299Y1954950D03*
X901999Y1987050D03*
X923999Y6050D03*
X917499Y21550D03*
X909499D03*
X909999Y35550D03*
X916499Y36050D03*
X928499Y51550D03*
X920900Y54700D03*
X928999Y56050D03*
X928499Y60550D03*
X928999Y65550D03*
X913699Y484650D03*
Y503650D03*
X914699Y524650D03*
X918999Y641550D03*
Y656050D03*
Y673550D03*
X918499Y693050D03*
Y712050D03*
X921899Y744850D03*
X919499Y733050D03*
X921899Y759350D03*
Y776850D03*
X921399Y796350D03*
X922399Y836350D03*
X921399Y815350D03*
X920399Y854850D03*
Y869350D03*
Y886850D03*
X919899Y906350D03*
Y925350D03*
X920899Y946350D03*
X921499Y999050D03*
Y1013550D03*
Y1031050D03*
X920999Y1050550D03*
Y1069550D03*
X925499Y1103550D03*
X921999Y1090550D03*
X925499Y1118050D03*
Y1135550D03*
X924999Y1174050D03*
Y1155050D03*
X925999Y1195050D03*
Y1207050D03*
Y1221550D03*
Y1239050D03*
X925499Y1258550D03*
Y1277550D03*
X926499Y1298550D03*
X928499Y1325350D03*
X925999Y1365050D03*
Y1379550D03*
Y1397050D03*
X925499Y1416550D03*
Y1435550D03*
X926499Y1456550D03*
X924999Y1485550D03*
Y1471050D03*
Y1503050D03*
X914599Y1521650D03*
X924499Y1522550D03*
X910899Y1549250D03*
X924499Y1541550D03*
X909700Y1576400D03*
X925499Y1562550D03*
X925599Y1612050D03*
X923599Y1634350D03*
X908899Y1630050D03*
X914899Y1657550D03*
X922599Y1682150D03*
X911299Y1800850D03*
X928000Y1818500D03*
X922899Y1853650D03*
X914999Y1868050D03*
Y1887050D03*
X914899Y1912450D03*
X915499Y1899050D03*
X916599Y1942650D03*
X914899Y1972250D03*
X921499Y1986550D03*
X941499Y6550D03*
X929999Y32550D03*
X940499Y33050D03*
X945499Y33550D03*
X943499Y48050D03*
Y55050D03*
Y72550D03*
X942999Y61550D03*
Y66550D03*
X943499Y78050D03*
X939199Y142050D03*
X932499Y191550D03*
Y206050D03*
Y223550D03*
X931999Y243050D03*
Y262050D03*
X932999Y283050D03*
X933499Y304050D03*
Y318550D03*
Y336050D03*
X932999Y355550D03*
Y374550D03*
X933999Y395550D03*
X933499Y429550D03*
Y415050D03*
Y447050D03*
X932999Y466550D03*
Y485550D03*
X933999Y506550D03*
X935499Y539050D03*
Y524550D03*
Y556550D03*
X934999Y576050D03*
X950299Y599650D03*
X934999Y595050D03*
X950299Y614150D03*
X935999Y616050D03*
X950299Y631650D03*
X949799Y651150D03*
Y670150D03*
X950799Y691150D03*
X944499Y750050D03*
Y735550D03*
Y767550D03*
X943999Y787050D03*
Y806050D03*
X944999Y827050D03*
X942999Y845550D03*
Y877550D03*
Y860050D03*
X942499Y897050D03*
Y916050D03*
X943499Y937050D03*
X949299Y977450D03*
Y991950D03*
Y1009450D03*
X948799Y1047950D03*
Y1028950D03*
X949799Y1068950D03*
Y1080950D03*
X950699Y1107750D03*
Y1122250D03*
Y1139750D03*
X950199Y1159250D03*
Y1178250D03*
X950699Y1262750D03*
Y1281750D03*
X943799Y1342950D03*
Y1380850D03*
X944000Y1391900D03*
X946700Y1426500D03*
X944000Y1511300D03*
X943199Y1531650D03*
X933199Y1577550D03*
X944499Y1632650D03*
X950100Y1626100D03*
X940499Y1656950D03*
X941499Y1679550D03*
X931499Y1702050D03*
X949799Y1756250D03*
X941800Y1787700D03*
X941499Y1776250D03*
X934200Y1793500D03*
X932199Y1801850D03*
X937199Y1869950D03*
X937499Y1893850D03*
X938199Y1917150D03*
X947499Y1936050D03*
X930999Y1931050D03*
X945199Y1946350D03*
X930999Y1950050D03*
X946199Y1966650D03*
X931499Y1962050D03*
X930199Y1979550D03*
X936999Y1986550D03*
X960999Y6550D03*
X954799Y17850D03*
X965999Y47050D03*
Y56050D03*
Y64050D03*
X966499Y73050D03*
Y82050D03*
X968399Y137150D03*
X967399Y180350D03*
X958799Y167350D03*
X956099Y181350D03*
X952799Y199150D03*
Y213650D03*
Y231150D03*
X952299Y250650D03*
Y269650D03*
X953299Y290650D03*
X952799Y324650D03*
Y310150D03*
Y342150D03*
X952299Y361650D03*
Y380650D03*
X953299Y401650D03*
X954799Y434150D03*
Y419650D03*
Y451650D03*
X966199Y473350D03*
Y492350D03*
X951799Y489650D03*
X967199Y513350D03*
X951799Y504150D03*
Y521650D03*
X951299Y560150D03*
Y541150D03*
X966799Y566350D03*
X952299Y581150D03*
X966799Y585350D03*
X967799Y606350D03*
X969499Y639050D03*
Y653550D03*
Y671050D03*
X968999Y709550D03*
Y690550D03*
X969999Y730550D03*
Y744250D03*
Y758750D03*
Y776250D03*
X969499Y795750D03*
Y814750D03*
X970499Y835750D03*
Y847750D03*
Y862250D03*
X969999Y899250D03*
X970499Y879750D03*
X969999Y918250D03*
X970999Y939250D03*
X971999Y996550D03*
Y1011050D03*
Y1028550D03*
X971499Y1067050D03*
Y1048050D03*
X951199Y1211250D03*
Y1199250D03*
Y1225750D03*
Y1243250D03*
X951699Y1302750D03*
X965099Y1324350D03*
X952499Y1361850D03*
X964400Y1409700D03*
X972000Y1442000D03*
Y1437500D03*
X971700Y1448300D03*
X962500Y1436500D03*
Y1441000D03*
X952800Y1437500D03*
Y1442000D03*
X962200Y1447300D03*
X952500Y1448300D03*
X971500Y1467500D03*
X971700Y1457800D03*
Y1462300D03*
Y1452800D03*
X962000Y1466500D03*
X952300Y1467500D03*
X962200Y1451800D03*
X952500Y1452800D03*
X962200Y1456800D03*
Y1461300D03*
X952500Y1457800D03*
Y1462300D03*
X966000Y1475000D03*
X958800Y1472500D03*
X966000Y1479500D03*
Y1484000D03*
X958800Y1477000D03*
Y1481500D03*
X965700Y1489300D03*
X958500Y1486800D03*
X960200Y1495300D03*
X951500D03*
X960049Y1500300D03*
X951349D03*
X960049Y1504800D03*
X951349D03*
X966600Y1529100D03*
X961400Y1528700D03*
X961900Y1522400D03*
X967100Y1522800D03*
X962100Y1516000D03*
X967300Y1516400D03*
X961600Y1534400D03*
X972000Y1547500D03*
X966100D03*
X960900Y1547100D03*
X961400Y1540800D03*
X966600Y1541200D03*
X966800Y1534800D03*
X961600Y1552900D03*
X966800Y1553300D03*
X972000Y1566000D03*
X966100D03*
X960900Y1565600D03*
X961400Y1559300D03*
X966600Y1559700D03*
X961900Y1572400D03*
X967100Y1572800D03*
X966400Y1585500D03*
X961200Y1585100D03*
X961700Y1578800D03*
X966900Y1579200D03*
X966500Y1592000D03*
X961300Y1591600D03*
X966300Y1598400D03*
X961100Y1598000D03*
X960600Y1604300D03*
X971700Y1604700D03*
X965800D03*
X957799Y1646950D03*
X955499Y1690850D03*
X958799Y1715750D03*
X965349Y1742000D03*
X954499Y1783550D03*
X971000Y1803000D03*
X971500Y1871500D03*
X966799Y1892150D03*
X955499Y1893050D03*
Y1902050D03*
X954099Y1915450D03*
X955799Y1951950D03*
X971499Y1956050D03*
Y1937050D03*
X953799Y1977950D03*
X971499Y1965050D03*
X956499Y1986050D03*
X976499Y6550D03*
X974699Y21450D03*
X991399Y22450D03*
X977399Y44050D03*
X974699Y64650D03*
X991999Y56050D03*
X983099Y83650D03*
X977699Y109150D03*
X981099Y123450D03*
X988699Y174350D03*
X982999Y189050D03*
Y203550D03*
Y221050D03*
X982499Y240550D03*
Y259550D03*
X983499Y280550D03*
X983999Y301550D03*
Y316050D03*
Y333550D03*
X983499Y353050D03*
Y372050D03*
X983999Y412550D03*
X984499Y393050D03*
X983999Y427050D03*
Y444550D03*
X983499Y464050D03*
Y483050D03*
X984499Y504050D03*
X985999Y536550D03*
Y522050D03*
Y554050D03*
X985499Y573550D03*
Y592550D03*
X986499Y613550D03*
X992999Y894550D03*
Y913550D03*
X972499Y1088050D03*
X975999Y1101050D03*
Y1115550D03*
X975499Y1152550D03*
X975999Y1133050D03*
X975499Y1171550D03*
X976499Y1192550D03*
Y1204550D03*
Y1219050D03*
Y1236550D03*
X975999Y1256050D03*
Y1275050D03*
X976999Y1296050D03*
X975100Y1342600D03*
X976499Y1362550D03*
Y1377050D03*
X992500Y1397300D03*
X973500Y1483000D03*
Y1478500D03*
X973200Y1488300D03*
X973500Y1474000D03*
X972549Y1502300D03*
Y1506800D03*
X972700Y1497300D03*
X973200Y1516400D03*
X972500Y1529100D03*
X973000Y1522800D03*
X972700Y1534800D03*
X972500Y1541200D03*
X972700Y1553300D03*
X972500Y1559700D03*
X973000Y1572800D03*
X972300Y1585500D03*
X972800Y1579200D03*
X972400Y1592000D03*
X972200Y1598400D03*
X989999Y1718050D03*
X993299Y1734350D03*
X976600Y1757100D03*
X976399Y1772250D03*
Y1791150D03*
X974699Y1914450D03*
X991999Y1915750D03*
X992299Y1929050D03*
X980999Y1933350D03*
X987999Y1949050D03*
Y1971950D03*
X989999Y1962650D03*
X973999Y1986550D03*
X995999Y6050D03*
X1013499Y6550D03*
X1002699Y40050D03*
X1005299Y71350D03*
X994399Y101250D03*
X1010599Y115550D03*
X1005299Y179950D03*
Y194450D03*
Y211950D03*
X1004799Y231450D03*
Y250450D03*
X1005799Y271450D03*
X1005299Y305450D03*
Y290950D03*
Y322950D03*
X1004799Y342450D03*
Y361450D03*
X1005799Y382450D03*
X1007299Y400450D03*
Y432450D03*
Y414950D03*
X1000699Y463350D03*
Y482350D03*
X1001699Y503350D03*
X1003999Y526850D03*
X1003499Y546350D03*
Y565350D03*
X1004499Y586350D03*
X1005999Y618850D03*
Y604350D03*
Y636350D03*
X994999Y747550D03*
Y733050D03*
Y765050D03*
X994499Y784550D03*
Y803550D03*
X995499Y824550D03*
X993499Y857550D03*
Y843050D03*
Y875050D03*
X994499Y941550D03*
X993999Y934550D03*
X994499Y956050D03*
Y973550D03*
X993999Y993050D03*
Y1012050D03*
X994999Y1033050D03*
Y1045050D03*
X998599Y1110950D03*
Y1096450D03*
Y1128450D03*
X998099Y1147950D03*
Y1166950D03*
X999099Y1187950D03*
Y1214450D03*
Y1199950D03*
Y1231950D03*
X998599Y1251450D03*
Y1270450D03*
X999599Y1291450D03*
X996500Y1324800D03*
X1000700Y1358100D03*
X994200Y1421500D03*
X1008999Y1702450D03*
X1008599Y1716050D03*
X994999Y1748950D03*
X999999Y1775250D03*
X1009999Y1797450D03*
X993499Y1805550D03*
X1007599Y1818450D03*
X993499Y1824550D03*
X1003599Y1846650D03*
X993499Y1833550D03*
X1011299Y1860650D03*
X995699Y1858950D03*
X1001599Y1921450D03*
X1000999Y1946350D03*
X1002500Y1953500D03*
X1005000Y1980500D03*
X994999Y1986550D03*
X1022000Y15500D03*
X1020499Y50550D03*
X1020999Y33050D03*
Y70050D03*
Y85550D03*
Y105050D03*
X1020499Y122550D03*
X1020999Y158550D03*
X1021499Y141050D03*
Y178050D03*
Y193550D03*
Y213050D03*
X1020999Y230550D03*
Y252050D03*
X1020499Y269550D03*
X1020999Y304550D03*
Y289050D03*
Y324050D03*
X1020499Y341550D03*
Y391550D03*
X1020999Y374050D03*
Y411050D03*
Y426550D03*
Y446050D03*
X1020499Y463550D03*
X1021999Y486550D03*
X1021499Y504050D03*
X1021999Y539050D03*
Y523550D03*
Y558550D03*
X1021499Y576050D03*
X1020499Y623050D03*
X1020999Y605550D03*
Y642550D03*
Y658050D03*
Y677550D03*
X1020499Y695050D03*
X1020999Y720050D03*
X1020499Y737550D03*
X1020999Y772550D03*
Y757050D03*
Y792050D03*
X1020499Y809550D03*
Y828050D03*
X1019999Y845550D03*
X1020499Y865050D03*
Y880550D03*
X1019999Y917550D03*
X1020499Y900050D03*
X1019999Y934050D03*
X1019499Y951550D03*
X1019999Y971050D03*
Y986550D03*
X1019499Y1023550D03*
X1019999Y1006050D03*
Y1043050D03*
Y1058550D03*
X1020499Y1081550D03*
X1019999Y1099050D03*
X1020499Y1118550D03*
Y1134050D03*
X1019499Y1146050D03*
X1018999Y1163550D03*
X1019499Y1183050D03*
Y1198550D03*
X1016999Y1219050D03*
X1016499Y1236550D03*
X1016999Y1256050D03*
Y1271550D03*
X1016499Y1301050D03*
X1022599Y1322950D03*
X1023300Y1344400D03*
X1024300Y1365200D03*
Y1393600D03*
X1022299Y1715750D03*
X1016899Y1731650D03*
X1020299Y1746650D03*
X1015299Y1765950D03*
X1026899Y1768550D03*
X1022999Y1784550D03*
X1022499Y1802050D03*
X1022999Y1821550D03*
Y1837050D03*
X1020999Y1860050D03*
X1020499Y1877550D03*
X1020999Y1912550D03*
Y1897050D03*
X1017499Y1954550D03*
X1017999Y1937050D03*
X1023000Y1973000D03*
X1017999Y1987050D03*
G54D21*
G01X26662Y861550D02*
X35599D01*
X36524Y862475D01*
Y1008225D01*
X18299Y1026450D01*
Y1036150D01*
X36554Y1054405D01*
Y1437858D01*
X25594Y1448818D01*
Y1463704D01*
X36290Y1474400D01*
Y1488925D01*
X27940Y1497275D01*
Y1527509D01*
X24500Y1530949D01*
Y1536935D01*
X27807Y1540242D01*
Y1546642D01*
X29215Y1548050D01*
Y1559815D01*
X32974Y1563574D01*
Y1596074D01*
X35424Y1598524D01*
Y1607143D01*
X36709Y1608428D01*
Y1706923D01*
X20199Y1723433D01*
Y1797552D01*
X27247Y1804600D01*
Y1814925D01*
X22624Y1819548D01*
Y1831175D01*
X31333Y1839884D01*
X47166D01*
G01X61400Y452600D02*
X38700Y429900D01*
Y384600D01*
X28100Y374000D01*
G01X65000Y455500D02*
X57900D01*
X37050Y434650D01*
Y425950D01*
X28900Y417800D01*
G01X27199Y539600D02*
X36598D01*
X51680Y554682D01*
Y588452D01*
X50374Y589758D01*
Y602342D01*
X96875Y648843D01*
Y832375D01*
X98000Y833500D01*
G01X80500Y817000D02*
X84500Y813000D01*
Y657470D01*
X43830Y616800D01*
X32100D01*
X26800Y611500D01*
G01X41500Y642800D02*
X41498D01*
X40500Y643798D01*
Y651100D01*
X31700Y659900D01*
X25600D01*
X21600Y663900D01*
Y690400D01*
X23500Y692300D01*
X30724D01*
X31824Y693400D01*
Y702400D01*
X28700Y705524D01*
Y745700D01*
X31074Y748074D01*
Y785275D01*
X29299Y787050D01*
Y808750D01*
X34524Y813975D01*
Y852141D01*
X41524Y859141D01*
Y1047240D01*
X41526Y1047242D01*
Y1050372D01*
X41524Y1050374D01*
Y1536525D01*
X38208Y1539841D01*
Y1569841D01*
G01X39000Y1573500D02*
Y1573495D01*
X40033Y1572462D01*
Y1540350D01*
X43174Y1537209D01*
Y1051058D01*
X43176Y1051056D01*
Y1046558D01*
X43174Y1046556D01*
Y851275D01*
X36174Y844275D01*
Y813007D01*
X30949Y807782D01*
Y787734D01*
X32724Y785959D01*
Y747390D01*
X30350Y745016D01*
Y706208D01*
X33474Y703084D01*
Y692700D01*
X25600Y684826D01*
Y666500D01*
X28138Y663962D01*
X40262D01*
X46824Y657400D01*
Y640324D01*
X41500Y635000D01*
G01X47101Y632355D02*
X54458Y639712D01*
Y652100D01*
X38679Y667879D01*
X35140D01*
X31275Y671744D01*
Y681866D01*
X36774Y687365D01*
Y704452D01*
X34374Y706852D01*
Y742500D01*
X59756Y767882D01*
Y815036D01*
X59723Y815069D01*
Y833358D01*
X62174Y835809D01*
Y839391D01*
X61372Y840193D01*
Y1014872D01*
X68324Y1021824D01*
Y1032000D01*
X61372Y1038952D01*
Y1561866D01*
X59722Y1563516D01*
Y1739927D01*
X43925Y1755724D01*
Y1767890D01*
G01X27700Y682700D02*
X29527D01*
X35124Y688297D01*
Y703768D01*
X32724Y706168D01*
Y743184D01*
X34374Y744834D01*
Y786643D01*
X33475Y787542D01*
Y801143D01*
X37216Y804884D01*
Y807951D01*
G01X35300Y789375D02*
X46887D01*
X58106Y800594D01*
Y814352D01*
X58073Y814385D01*
Y834042D01*
X60524Y836493D01*
Y838707D01*
X59722Y839509D01*
Y1561182D01*
X58072Y1562832D01*
Y1738228D01*
X42300Y1754000D01*
X42275D01*
G01X37416Y799033D02*
X41474Y803091D01*
Y822757D01*
X41451Y822780D01*
Y838577D01*
X43221Y840347D01*
Y846654D01*
X46522Y849955D01*
Y1555709D01*
X44872Y1557359D01*
Y1708400D01*
X26799Y1726473D01*
Y1794816D01*
X34599Y1802616D01*
Y1805123D01*
G01X29899Y1821050D02*
X32197Y1818752D01*
Y1802548D01*
X25149Y1795500D01*
Y1725789D01*
X41659Y1709279D01*
Y1606376D01*
X40374Y1605091D01*
Y1592949D01*
X42063Y1591260D01*
Y1540654D01*
X44824Y1537893D01*
Y1051742D01*
X44826Y1051740D01*
Y1045874D01*
X44824Y1045872D01*
Y850591D01*
X37824Y843591D01*
Y812075D01*
X37099Y811350D01*
G01X35559Y795112D02*
X36842D01*
X43124Y801394D01*
Y823441D01*
X43101Y823464D01*
Y837893D01*
X44871Y839663D01*
Y845970D01*
X48172Y849271D01*
Y1556394D01*
X46522Y1558044D01*
Y1709084D01*
X28449Y1727157D01*
Y1793100D01*
X32099Y1796750D01*
Y1797150D01*
G01X31699Y814350D02*
Y851650D01*
X39874Y859825D01*
Y1047924D01*
X39876Y1047926D01*
Y1049688D01*
X39874Y1049690D01*
Y1524000D01*
X35899Y1527976D01*
Y1547617D01*
X33071Y1550445D01*
Y1559003D01*
X36274Y1562206D01*
Y1588250D01*
X38724Y1590700D01*
Y1605775D01*
X40009Y1607060D01*
Y1708595D01*
X23499Y1725105D01*
Y1796184D01*
X30547Y1803232D01*
Y1816293D01*
X26099Y1820741D01*
Y1824950D01*
G01X23299Y863050D02*
Y862332D01*
X25906Y859725D01*
X36108D01*
X38202Y861819D01*
Y1044600D01*
X38204Y1044602D01*
Y1447325D01*
X27244Y1458285D01*
Y1463020D01*
X37940Y1473716D01*
Y1489609D01*
X35174Y1492375D01*
Y1495307D01*
X37824Y1497957D01*
Y1523715D01*
X36719Y1524821D01*
X34899Y1526641D01*
X34249Y1527292D01*
Y1546933D01*
X31421Y1549761D01*
Y1559687D01*
X34624Y1562890D01*
Y1588934D01*
X37074Y1591384D01*
Y1606459D01*
X38359Y1607744D01*
Y1707607D01*
X21849Y1724117D01*
Y1796868D01*
X28897Y1803916D01*
Y1815609D01*
X24274Y1820232D01*
Y1830259D01*
X31340Y1837325D01*
X45724D01*
X46499Y1836550D01*
G01X20999Y1352050D02*
X21499Y1351550D01*
Y1321050D01*
X20999Y1320550D01*
G01X44046Y799554D02*
X44774Y800282D01*
Y824125D01*
X44751Y824148D01*
Y837209D01*
X46521Y838979D01*
Y845286D01*
X49822Y848587D01*
Y1557078D01*
X48172Y1558728D01*
Y1709769D01*
X30274Y1727667D01*
Y1787238D01*
G01X28550Y1828153D02*
Y1825414D01*
X37701Y1816263D01*
Y1803384D01*
X34099Y1799782D01*
Y1787084D01*
X32200Y1785185D01*
Y1728075D01*
X49822Y1710453D01*
Y1559412D01*
X51472Y1557762D01*
Y837323D01*
X50399Y836250D01*
G01X46700Y820100D02*
X48949Y822349D01*
Y832150D01*
X53122Y836323D01*
Y1558446D01*
X51472Y1560096D01*
Y1711727D01*
X33850Y1729349D01*
Y1784501D01*
X35749Y1786400D01*
Y1796442D01*
X38878Y1799571D01*
G01X51100Y806300D02*
Y811818D01*
X51725Y812443D01*
Y813957D01*
X50599Y815083D01*
Y831466D01*
X54772Y835639D01*
Y1559130D01*
X53122Y1560780D01*
Y1712411D01*
X35500Y1730033D01*
Y1783275D01*
X35675Y1783450D01*
G01X56281Y801350D02*
X56383Y801452D01*
Y807584D01*
X53375Y810591D01*
Y812469D01*
X55899Y814993D01*
Y816507D01*
X52249Y820157D01*
Y830782D01*
X56422Y834955D01*
Y1559814D01*
X54772Y1561464D01*
Y1736328D01*
X39900Y1751200D01*
G01D02*
X38800Y1752300D01*
Y1773009D01*
X39324Y1773533D01*
Y1780623D01*
G01X41200Y1747050D02*
Y1747318D01*
X37150Y1751368D01*
Y1781901D01*
X38094Y1782845D01*
Y1785840D01*
G01X34099Y1822850D02*
X42021Y1814928D01*
X42448Y1814500D01*
Y1796601D01*
X47599Y1791450D01*
X48049D01*
G01X80099Y1817250D02*
X63199D01*
X44774Y1835675D01*
X38943D01*
X37874Y1834606D01*
Y1832126D01*
X49874Y1820126D01*
Y1782425D01*
X46999Y1779550D01*
G01X72362Y849550D02*
Y974079D01*
X84875Y986592D01*
Y1006291D01*
X84525Y1006641D01*
Y1190935D01*
X86525Y1192935D01*
Y1250624D01*
X75040Y1262109D01*
Y1381257D01*
X84875Y1391092D01*
Y1411010D01*
X71272Y1424613D01*
Y1565970D01*
X70724Y1566518D01*
Y1625898D01*
X88175Y1643349D01*
Y1658510D01*
X69622Y1677063D01*
Y1746211D01*
X52600Y1763233D01*
Y1820949D01*
X39699Y1833850D01*
G01X68000Y546500D02*
X55000Y559500D01*
Y589800D01*
X53674Y591126D01*
Y600974D01*
X101450Y648750D01*
Y839850D01*
X98700Y842600D01*
G01Y822550D02*
Y819908D01*
X99800Y818808D01*
Y649434D01*
X52024Y601658D01*
Y590442D01*
X53350Y589116D01*
Y558569D01*
X67244Y544675D01*
X72175D01*
X72500Y545000D01*
G01X42202Y608195D02*
Y609544D01*
X94500Y661842D01*
Y836000D01*
X80000Y850500D01*
X76978D01*
X76540Y850938D01*
G01X75500Y847700D02*
X75800Y848000D01*
X79500D01*
X87175Y840325D01*
Y657275D01*
X41400Y611500D01*
G01X48049Y1791450D02*
X41574Y1784975D01*
Y1773449D01*
X40450Y1772325D01*
Y1753243D01*
X56422Y1737271D01*
Y1562148D01*
X58072Y1560498D01*
Y838825D01*
X58699Y838198D01*
Y837250D01*
G01X76999Y1196550D02*
Y1234101D01*
X63022Y1248078D01*
Y1562550D01*
X61372Y1564200D01*
Y1742077D01*
X45799Y1757650D01*
G01X43751Y1780559D02*
X44100Y1780210D01*
Y1773641D01*
X42100Y1771641D01*
Y1754175D01*
X42275Y1754000D01*
G01X68860Y838706D02*
Y839488D01*
X67787Y840561D01*
X67237Y841112D01*
Y988354D01*
X77049Y998166D01*
Y1006383D01*
X78975Y1008309D01*
Y1023659D01*
X72274Y1030360D01*
Y1185686D01*
X80474Y1193886D01*
Y1235426D01*
X70090Y1245810D01*
Y1397342D01*
X76423Y1403675D01*
Y1412460D01*
X66322Y1422561D01*
Y1563918D01*
X65774Y1564466D01*
Y1627950D01*
X83225Y1645401D01*
Y1656458D01*
X64672Y1675011D01*
Y1744159D01*
X47440Y1761391D01*
G01X69499Y842950D02*
X68887Y843562D01*
Y987670D01*
X78699Y997482D01*
Y1005699D01*
X80625Y1007625D01*
Y1024426D01*
X77174Y1027877D01*
Y1188252D01*
X83225Y1194303D01*
Y1249256D01*
X71740Y1260741D01*
Y1396657D01*
X78073Y1402990D01*
Y1413144D01*
X67972Y1423245D01*
Y1564602D01*
X67424Y1565150D01*
Y1627266D01*
X84875Y1644717D01*
Y1657142D01*
X66322Y1675695D01*
Y1744843D01*
X49265Y1761900D01*
Y1767344D01*
X47604Y1769005D01*
G01X45782Y1771877D02*
X45750Y1771845D01*
Y1767133D01*
X45575Y1766958D01*
Y1760674D01*
X63022Y1743227D01*
Y1564884D01*
X64672Y1563234D01*
Y1421876D01*
X74773Y1411775D01*
Y1404359D01*
X68440Y1398026D01*
Y1245125D01*
X78824Y1234741D01*
Y1194570D01*
X70624Y1186370D01*
Y1029676D01*
X77325Y1022975D01*
Y1008993D01*
X75399Y1007067D01*
Y999250D01*
X63499Y987350D01*
Y843050D01*
G01X65500Y817700D02*
Y821771D01*
X63023Y824248D01*
Y830287D01*
X71324Y838588D01*
Y845375D01*
X70537Y846162D01*
Y974588D01*
X83225Y987276D01*
Y1005607D01*
X82875Y1005957D01*
Y1191619D01*
X84875Y1193619D01*
Y1249940D01*
X73390Y1261425D01*
Y1381941D01*
X83225Y1391776D01*
Y1410326D01*
X69622Y1423929D01*
Y1565286D01*
X69074Y1565834D01*
Y1626582D01*
X86525Y1644033D01*
Y1657826D01*
X67972Y1676379D01*
Y1745527D01*
X50915Y1762584D01*
Y1771934D01*
X47499Y1775350D01*
G01X74220Y854150D02*
Y973603D01*
X86525Y985908D01*
Y1007393D01*
X86175Y1007743D01*
Y1009257D01*
X88175Y1011257D01*
Y1323400D01*
X78500Y1333075D01*
Y1350960D01*
X80440Y1352900D01*
Y1379491D01*
X86525Y1385576D01*
Y1411694D01*
X72922Y1425297D01*
Y1566654D01*
X72374Y1567202D01*
Y1625214D01*
X89825Y1642665D01*
Y1659194D01*
X71272Y1677747D01*
Y1746895D01*
X54250Y1763917D01*
Y1822698D01*
X43099Y1833850D01*
G01X65999Y216050D02*
X95872D01*
X130042Y181880D01*
X146560Y165360D01*
X151506Y160414D01*
X225157D01*
X228218Y163475D01*
X229980D01*
X233041Y160414D01*
X263842D01*
X321426Y102830D01*
Y100709D01*
X358999Y63136D01*
Y61550D01*
G01X62405Y820300D02*
Y821496D01*
X61373Y822528D01*
Y832674D01*
X63824Y835125D01*
Y842240D01*
X63499Y842565D01*
Y843050D01*
G01X90000Y993100D02*
X90125Y993225D01*
Y1324700D01*
X82390Y1332435D01*
Y1348990D01*
X86700Y1353300D01*
X89300D01*
X92600Y1356600D01*
Y1408377D01*
X85853Y1415124D01*
X83000Y1417978D01*
X81982Y1418997D01*
Y1542752D01*
X80043Y1544691D01*
G01X78600Y1561900D02*
X77100Y1563400D01*
Y1571800D01*
X79500Y1574200D01*
X90200D01*
X103400Y1587400D01*
X333752D01*
X338700Y1592348D01*
X930632D01*
X976125Y1637841D01*
Y1659125D01*
X977500Y1660500D01*
G01X978000Y1668000D02*
X974175Y1664175D01*
Y1638649D01*
X929825Y1594299D01*
X337892D01*
X332943Y1589350D01*
X102350D01*
X89400Y1576400D01*
X78758D01*
X75000Y1572642D01*
Y1561800D01*
G01X74400Y1574800D02*
X77950Y1578350D01*
X88350D01*
X101300Y1591300D01*
X101542D01*
X101543Y1591301D01*
X103158D01*
X103159Y1591300D01*
X332134D01*
X337083Y1596249D01*
X929017D01*
X966975Y1634207D01*
Y1644826D01*
X965775Y1646026D01*
Y1662475D01*
X974000Y1670700D01*
G01X74800Y1584700D02*
X92365D01*
X100615Y1592950D01*
X100858D01*
X100859Y1592951D01*
X103842D01*
X103843Y1592950D01*
X331450D01*
X336399Y1597899D01*
X928333D01*
X965150Y1634716D01*
Y1639500D01*
G01X74500Y1692000D02*
X75300Y1691200D01*
Y1676053D01*
X91475Y1659878D01*
Y1641981D01*
X74024Y1624530D01*
Y1615176D01*
X94600Y1594600D01*
X100174D01*
X100175Y1594601D01*
X104526D01*
X104527Y1594600D01*
X330766D01*
X335716Y1599550D01*
X927650D01*
X961702Y1633602D01*
Y1636102D01*
G01X107000Y604800D02*
Y605400D01*
X106000Y606400D01*
Y911500D01*
X95500Y922000D01*
Y958000D01*
X102000Y964500D01*
Y968400D01*
X102100Y968500D01*
G01X99000Y965000D02*
X93000Y959000D01*
Y920000D01*
X103702Y909298D01*
Y601398D01*
X105100Y600000D01*
G01X102100Y968500D02*
Y968605D01*
X113650Y980155D01*
Y1050650D01*
X125000Y1062000D01*
Y1066500D01*
X127500Y1069000D01*
X142500D01*
X145951Y1072451D01*
Y1108892D01*
X97200Y1157643D01*
Y1309500D01*
X114200Y1326500D01*
Y1337500D01*
X117300Y1340600D01*
Y1363800D01*
X115400Y1365700D01*
Y1399600D01*
X92700Y1422300D01*
Y1549751D01*
X97499Y1554550D01*
G01X99000Y965000D02*
X99900Y965900D01*
Y969163D01*
X111700Y980963D01*
Y1051700D01*
X122000Y1062000D01*
Y1068000D01*
X125500Y1071500D01*
X141000D01*
X144000Y1074500D01*
Y1108084D01*
X95250Y1156834D01*
Y1335850D01*
X98000Y1338600D01*
Y1362692D01*
X106100Y1370792D01*
Y1401300D01*
X86424Y1420976D01*
Y1547475D01*
X96999Y1558050D01*
G01X83932Y1544705D02*
Y1419805D01*
X84731Y1419006D01*
X90425Y1413310D01*
X103100Y1400635D01*
Y1370550D01*
X96050Y1363500D01*
Y1339950D01*
X92075Y1335975D01*
Y996625D01*
X92600Y996100D01*
G01X90324Y1538800D02*
Y1421576D01*
X108050Y1403850D01*
Y1368550D01*
X104500Y1365000D01*
Y1323163D01*
X102700Y1321363D01*
G01X96200Y1550100D02*
Y1532300D01*
X98000Y1530500D01*
X152000D01*
X160500Y1539000D01*
X319050D01*
X343652Y1514398D01*
X390999D01*
G01X100800Y1536450D02*
X152950D01*
X172550Y1556050D01*
X279999D01*
G01X354500Y1559500D02*
X354000Y1559000D01*
X173000D01*
X153850Y1539850D01*
X99899D01*
G01X100000Y1546650D02*
X100899D01*
X108500Y1554251D01*
Y1562057D01*
X126924Y1580481D01*
X396068D01*
X400999Y1575550D01*
G01X982050Y1649302D02*
Y1636340D01*
X932710Y1587000D01*
X340900D01*
X336050Y1582150D01*
X126259D01*
X106850Y1562741D01*
Y1556300D01*
X98074Y1547524D01*
Y1534379D01*
X98144Y1534309D01*
G01X89373Y1561073D02*
X112100Y1583800D01*
X335366D01*
X340216Y1588650D01*
X932026D01*
X979725Y1636349D01*
Y1651225D01*
X981500Y1653000D01*
G01X85600Y1561500D02*
X109550Y1585450D01*
X334682D01*
X339532Y1590300D01*
X931342D01*
X978075Y1637033D01*
Y1656875D01*
X980800Y1659600D01*
G01X153500Y834600D02*
X152800D01*
X121200Y803000D01*
Y562150D01*
X137899Y545451D01*
G01X120507Y1317050D02*
X125007Y1312550D01*
X156599D01*
X167099Y1323050D01*
X367149D01*
X370149Y1320050D01*
G01X345424Y1310050D02*
X341999D01*
X341924Y1309975D01*
X110261D01*
X107999Y1307713D01*
G01X121000Y1364000D02*
X120508D01*
X119499Y1362991D01*
Y1339050D01*
G01X152633Y1677967D02*
X149166D01*
X122890Y1704243D01*
X122642D01*
G01X377900Y1703800D02*
X329600D01*
X305800Y1680000D01*
X170730D01*
X170604Y1679874D01*
X168596D01*
X168470Y1680000D01*
X149468D01*
X119074Y1710394D01*
Y1714101D01*
X112562Y1720613D01*
G01X251500Y1136700D02*
X150700D01*
X138600Y1124600D01*
G01X150750Y540416D02*
X829917Y216200D01*
G01X833576Y215432D02*
X830454Y218554D01*
X151900Y542366D01*
X149942D01*
X148800Y541224D01*
Y537700D01*
X149000Y537500D01*
G01X199900Y554050D02*
X161450D01*
X154500Y561000D01*
Y584551D01*
X165700Y595751D01*
Y750876D01*
X156026Y760550D01*
Y836823D01*
X154799Y838050D01*
G01X364499Y1099050D02*
X337999D01*
X329049Y1090100D01*
X240650D01*
X232750Y1098000D01*
X222500D01*
X213050Y1088550D01*
X167270D01*
X164700Y1085980D01*
Y1085400D01*
G01X711652Y1822109D02*
X162000Y1596550D01*
X157400D01*
G01X160200Y1598500D02*
X711848Y1825504D01*
G01X199149Y1362900D02*
X205900D01*
X291500Y1448500D01*
Y1509500D01*
X295000Y1513000D01*
G01X218499Y190550D02*
X292999Y265050D01*
Y292550D01*
X293999Y293550D01*
G01X371500Y880600D02*
Y888500D01*
X367500Y892500D01*
X213850D01*
X211750Y894600D01*
G01X221800Y1069300D02*
X228500Y1076000D01*
X228769D01*
X228794Y1076025D01*
X240075D01*
X269050Y1047050D01*
X339735D01*
X340699Y1046086D01*
G01X283499Y1556050D02*
X283924Y1556475D01*
X363899D01*
X366149Y1554225D01*
Y1554050D01*
G01X320499Y798050D02*
X335624Y782925D01*
Y689625D01*
X394649Y630600D01*
G01X330540Y795509D02*
X342149Y783900D01*
Y729819D01*
X409074Y662894D01*
X466236D01*
X793324Y335806D01*
Y332294D01*
X784080Y323050D01*
X772499D01*
G01X771105Y722789D02*
X408260D01*
X329499Y801550D01*
G01X344520Y406329D02*
X400499D01*
G01X771999Y1124550D02*
X743999Y1096550D01*
X345499D01*
G01X347324Y1524000D02*
X347874Y1524550D01*
X740500D01*
X746950Y1531000D01*
X773592D01*
X774542Y1530050D01*
G01X986400Y1639302D02*
X985650Y1638552D01*
Y1635272D01*
X933278Y1582900D01*
X349774D01*
G01X984211Y1667500D02*
X984500D01*
X984000Y1667000D01*
Y1635956D01*
X932944Y1584900D01*
X354000D01*
G01X371999Y549300D02*
X574667D01*
X790917Y333050D01*
X791499D01*
G01X791999Y733050D02*
X783824Y724875D01*
Y724794D01*
X766705Y707675D01*
X765618D01*
X755868Y697925D01*
X749118D01*
X748493Y698550D01*
X375999D01*
G01X792154Y1135926D02*
X790778Y1134550D01*
X771999D01*
X760999Y1123550D01*
X372999D01*
G01X793999Y1541050D02*
X792700D01*
X779875Y1528225D01*
X773785D01*
X772660Y1529350D01*
X747634D01*
X736334Y1518050D01*
X391251D01*
X390999Y1517798D01*
G54D12*
X29531Y309549D03*
Y1029510D03*
X17720Y1903132D03*
X271657Y267699D03*
Y673210D03*
Y1078722D03*
Y1484234D03*
Y1889746D03*
X994098Y149588D03*
Y673210D03*
Y1068880D03*
G54D13*
X14999Y1936050D03*
Y1940050D03*
X8499Y1937550D03*
X15099Y1944050D03*
X5303Y1947050D03*
X11703Y1951946D03*
X17499Y1961050D03*
X29699Y388484D03*
X29599Y382884D03*
X23399Y373931D03*
Y389679D03*
X23499Y381831D03*
X26299Y383854D03*
Y387629D03*
X28100Y374000D03*
X26299Y399601D03*
Y403376D03*
X29999Y398684D03*
X29899Y404384D03*
X23799Y405684D03*
X23499Y397579D03*
X35900Y412600D03*
X26524Y426720D03*
X26399Y423322D03*
X28672Y429356D03*
X29365Y421169D03*
X23399Y429051D03*
X28900Y417800D03*
X26492Y439350D03*
X26599Y442749D03*
X26899Y454850D03*
X28700Y451900D03*
X28800Y436700D03*
X28700Y445700D03*
X23399Y444799D03*
X23499Y452699D03*
Y436951D03*
X26799Y458497D03*
X26486Y462648D03*
X26499Y466250D03*
X29500Y460800D03*
X23499Y468447D03*
X23399Y476295D03*
Y460547D03*
X26299Y478404D03*
X26515Y481798D03*
X23399Y492043D03*
X23499Y484195D03*
X36499Y517775D03*
X26399Y501966D03*
Y505741D03*
X28600Y508500D03*
X38400Y514955D03*
X28664Y499429D03*
X23499Y515691D03*
Y499943D03*
X23399Y507791D03*
X36499Y521550D03*
X35338Y524746D03*
X26691Y532701D03*
X22800Y539600D03*
X23399Y523539D03*
X23499Y531439D03*
X26599Y525648D03*
Y529302D03*
X27199Y539600D03*
X39217Y554750D03*
X33307Y557938D03*
X26199Y547176D03*
X29999Y557150D03*
X33699Y561850D03*
X36499Y566350D03*
X22699Y577950D03*
X22999Y565550D03*
X28000Y578500D03*
X25581Y567763D03*
X27699Y573750D03*
X22978Y588571D03*
X28808Y593150D03*
X28700Y596549D03*
X27499Y620203D03*
Y623857D03*
X37999Y611550D03*
X26869Y616861D03*
X23499Y618053D03*
X23999Y609250D03*
X34976Y619250D03*
X26800Y611500D03*
X32200Y603710D03*
X31598Y607102D03*
X39600Y626984D03*
X38300Y633800D03*
X30712Y624971D03*
X29999Y640550D03*
X29819Y634951D03*
X23399Y641649D03*
X23799Y625950D03*
X23499Y633801D03*
X26568Y635950D03*
Y639604D03*
X30999Y656250D03*
Y650550D03*
X23499Y665297D03*
Y649549D03*
X23725Y657471D03*
X26737Y651957D03*
X26999Y656550D03*
X23699Y673150D03*
X23499Y681045D03*
X27687Y667447D03*
Y671101D03*
X27700Y682700D03*
X29999Y694550D03*
X25999Y694870D03*
X23999Y689050D03*
X27299Y783550D03*
X35300Y789375D03*
X32800Y803050D03*
X37416Y799033D03*
X37099Y811350D03*
X26299Y815050D03*
X35559Y795112D03*
X31699Y814350D03*
X37216Y807951D03*
X39649Y822000D03*
X29299Y836901D03*
X40400Y840792D03*
X22500Y853700D03*
X29600Y854000D03*
X23299Y863050D03*
X26662Y861550D03*
X25000Y858100D03*
X20400Y1048300D03*
X20999Y1320550D03*
X23700Y1354600D03*
X20999Y1352050D03*
X25000Y1357742D03*
X22851Y1374169D03*
X22999Y1366050D03*
X23499Y1381550D03*
X25507Y1372045D03*
X25558Y1368447D03*
X32550Y1392777D03*
X27499Y1387550D03*
X24499Y1389663D03*
X28499Y1391050D03*
X32333Y1389383D03*
X30500Y1395500D03*
X33321Y1414755D03*
X29786Y1414858D03*
X23499Y1421550D03*
X23999Y1413550D03*
X32451Y1411468D03*
X28999Y1411550D03*
X32094Y1448448D03*
X28697Y1448296D03*
X36198Y1446749D03*
X27099Y1444350D03*
X30999Y1438050D03*
X27999Y1430050D03*
X23499Y1445050D03*
X22999Y1437050D03*
X23999Y1429050D03*
X33206Y1432352D03*
X30499Y1434550D03*
X30378Y1462518D03*
X33915Y1462681D03*
X29069Y1459379D03*
X36791Y1460866D03*
X23028Y1468579D03*
X23499Y1460550D03*
X22999Y1453050D03*
X34465Y1481683D03*
X30999Y1482050D03*
X32520Y1485092D03*
X28999Y1478050D03*
X23599Y1476350D03*
X23277Y1484050D03*
X34099Y1497550D03*
X30499D03*
X27499Y1495050D03*
X36999Y1494550D03*
X22999Y1500050D03*
X23799Y1508050D03*
X24499Y1492050D03*
X30115Y1511900D03*
X33512Y1512051D03*
X29631Y1533063D03*
X31999Y1517846D03*
Y1521500D03*
X35245Y1522512D03*
X35999Y1514550D03*
X29765Y1515282D03*
X24423Y1527123D03*
X22999Y1515550D03*
X37999Y1530900D03*
X24199Y1523700D03*
X25247Y1546912D03*
X38500Y1534600D03*
X32099Y1535550D03*
X26705Y1534795D03*
X30199Y1545450D03*
X36340Y1558809D03*
X34896Y1555730D03*
X38208Y1569841D03*
X25521Y1563350D03*
X30520Y1572049D03*
X24999Y1569550D03*
X31149Y1568300D03*
X23608Y1572653D03*
X24323Y1559950D03*
X27123Y1572205D03*
X39000Y1573500D03*
X34999Y1595350D03*
X22699Y1594224D03*
X31099Y1595350D03*
X28899Y1613524D03*
X32299D03*
X26999Y1610550D03*
X34884Y1615734D03*
X23499Y1618050D03*
Y1610050D03*
Y1602050D03*
X33599Y1600200D03*
X29499Y1630050D03*
X32199Y1633124D03*
X34816Y1630953D03*
X22999Y1626050D03*
X23499Y1634050D03*
X32663Y1628181D03*
X31999Y1661127D03*
X28600Y1661039D03*
X29626Y1645002D03*
X33026Y1645051D03*
X27499Y1657050D03*
X32989Y1648451D03*
X26785Y1642089D03*
X23499Y1657050D03*
X23999Y1649550D03*
X23415Y1641634D03*
X34699Y1663300D03*
X22999Y1665550D03*
X24244Y1681868D03*
X22864Y1673550D03*
X32700Y1673300D03*
X32494Y1669706D03*
X29100Y1669500D03*
X30500Y1697500D03*
X39900Y1751200D03*
X41200Y1747050D03*
X30274Y1787238D03*
X35675Y1783450D03*
X39324Y1780623D03*
X38094Y1785840D03*
X38878Y1799571D03*
X34599Y1805123D03*
X37699Y1789850D03*
X37574Y1794050D03*
X31811Y1790271D03*
X40478Y1795820D03*
X32099Y1797150D03*
X28550Y1828153D03*
X29899Y1821050D03*
X34099Y1822850D03*
X35876Y1812350D03*
X34129Y1815267D03*
X36532Y1825352D03*
X36399Y1828750D03*
X26099Y1824950D03*
X29599Y1844350D03*
X22099Y1836609D03*
X28123Y1831527D03*
X25999Y1842550D03*
X39699Y1833850D03*
X28799Y1919060D03*
X23030Y1922038D03*
X26765Y1921945D03*
X34799Y1946750D03*
X38703Y1946754D03*
X25499Y1956050D03*
X32999Y1960555D03*
X31799Y1979050D03*
X41999Y200050D03*
X45800Y405200D03*
X61400Y452600D03*
X62497Y474346D03*
X60003Y534150D03*
X59999Y537550D03*
X42867Y548450D03*
X43099Y555850D03*
X46299Y552950D03*
X49799Y559150D03*
X42599Y567850D03*
X47543Y578340D03*
X44959Y575756D03*
X60076Y595777D03*
X55499Y595650D03*
X42202Y608195D03*
X41400Y611500D03*
X47626Y611300D03*
X45701Y607700D03*
X42709Y625607D03*
X41500Y642800D03*
X57800Y634300D03*
X44900Y642800D03*
X47101Y632355D03*
X41500Y635000D03*
X52500D03*
X48999Y642900D03*
X50410Y695801D03*
X50300Y699200D03*
X45100Y793100D03*
X44046Y799554D03*
X46887Y803413D03*
X51100Y806300D03*
X49900Y813200D03*
X56281Y801350D03*
X50399Y836250D03*
X46700Y820100D03*
X54074Y815750D03*
X62405Y820300D03*
X46576Y832951D03*
X48346Y844529D03*
X58699Y837250D03*
X44697Y1546793D03*
X44299Y1550950D03*
X42199Y1601050D03*
X47400Y1721700D03*
X42000Y1740100D03*
X47717Y1731337D03*
X47800Y1740500D03*
X45877Y1728477D03*
Y1724823D03*
X47000Y1737100D03*
X43600D03*
X42275Y1754000D03*
X45799Y1757650D03*
X47440Y1761391D03*
X47400Y1765250D03*
X43751Y1780559D03*
X46999Y1779550D03*
X46199Y1783050D03*
X43925Y1767890D03*
X47604Y1769005D03*
X45782Y1771877D03*
X47499Y1775350D03*
X47899Y1798650D03*
X48049Y1791450D03*
X42199Y1792250D03*
X46799Y1794900D03*
X61009Y1822340D03*
X60449Y1842550D03*
X46499Y1836550D03*
X47166Y1839884D03*
X43099Y1833850D03*
X57999Y1891050D03*
X42499Y1902550D03*
X48499Y1897050D03*
X44368Y1951450D03*
X44399Y1942250D03*
X42532Y1946783D03*
X53999Y1946650D03*
X50299D03*
X46565Y1946703D03*
X45999Y1971450D03*
X50499Y1961550D03*
X43462Y1961160D03*
X78700Y74200D03*
Y70700D03*
X74999Y70550D03*
Y74050D03*
X74499Y80650D03*
Y84050D03*
X65999Y216050D03*
X65000Y455500D03*
X62503Y470946D03*
X66199Y475184D03*
Y469884D03*
X77499Y469550D03*
X62978Y486217D03*
X63067Y489616D03*
X66299Y490784D03*
Y485484D03*
X77999Y493050D03*
X77499Y502550D03*
X65599Y514250D03*
X63499Y538550D03*
Y533050D03*
X68000Y546500D03*
X72500Y545000D03*
X81251Y607249D03*
Y619251D03*
X82499Y627050D03*
X80499Y664550D03*
X74499Y662050D03*
X78499Y654050D03*
X76999Y664550D03*
X81999Y668050D03*
X65500Y817700D03*
X80500Y817000D03*
X76540Y850938D03*
X75500Y847700D03*
X68860Y838706D03*
X69499Y842950D03*
X63499Y843050D03*
X74220Y854150D03*
X72362Y849550D03*
X80699Y1004450D03*
Y1000450D03*
X72000Y1013400D03*
X63273Y1023974D03*
X66499Y1025050D03*
X75500Y1012261D03*
X65486Y1031515D03*
X80000Y1090500D03*
X74500Y1097550D03*
X79899Y1104550D03*
X74399Y1111550D03*
X76999Y1196550D03*
X78499Y1273550D03*
X78613Y1282664D03*
X78779Y1302664D03*
Y1312664D03*
X77758Y1357742D03*
X76000Y1431100D03*
X80043Y1544691D03*
X78600Y1561900D03*
X75000Y1561800D03*
X74400Y1574800D03*
X80400Y1571766D03*
X82329Y1568117D03*
X79000Y1555500D03*
X82429D03*
X74800Y1584700D03*
X78100Y1688189D03*
X74500Y1692000D03*
X74400Y1778100D03*
X80099Y1817250D03*
X80999Y1836550D03*
X93999Y58550D03*
X92900Y66128D03*
X92999Y86128D03*
X97499Y90050D03*
X92999Y96128D03*
X89603Y132629D03*
X86899Y130567D03*
X86599Y126750D03*
X95350Y204550D03*
X89800Y208550D03*
X96900Y510000D03*
X93200Y510500D03*
X95500Y513400D03*
X98900D03*
X83700Y529500D03*
X88999Y538050D03*
X104502Y530552D03*
X86199Y536025D03*
Y532250D03*
X89000Y816500D03*
X90000Y826000D03*
X90500Y831500D03*
X98700Y822550D03*
X98000Y833500D03*
X98700Y842600D03*
X92999Y868550D03*
X92499Y876550D03*
X94999Y901550D03*
X89469Y935588D03*
X85999Y940429D03*
X86399Y937050D03*
X89499Y942850D03*
X102100Y968500D03*
X99000Y965000D03*
X104600Y980500D03*
X90000Y993100D03*
X92600Y996100D03*
X88000Y1008500D03*
X101499Y1072550D03*
X103999Y1216863D03*
X102900Y1196050D03*
X103686Y1223863D03*
X101541Y1262607D03*
X101399Y1292550D03*
X102700Y1321363D03*
X102000Y1341000D03*
X91279Y1340642D03*
X86165Y1339050D03*
X86890Y1342860D03*
X101500Y1352000D03*
X89999Y1348050D03*
X86890Y1346635D03*
X102350Y1344500D03*
Y1348154D03*
X97229Y1373337D03*
X97000Y1377600D03*
X98599Y1491350D03*
X100699Y1471050D03*
X100499Y1479650D03*
X83932Y1544705D03*
X100800Y1536450D03*
X96200Y1550100D03*
X99899Y1539850D03*
X100000Y1546650D03*
X90324Y1538800D03*
X97499Y1554550D03*
X98144Y1534309D03*
X96999Y1558050D03*
X89373Y1561073D03*
X85600Y1561500D03*
X95499Y1665418D03*
X92900Y1678176D03*
X93999Y1703050D03*
X92873Y1708176D03*
X92479Y1718176D03*
X89306Y1746856D03*
X89499Y1753575D03*
X85341Y1752245D03*
X85194Y1748848D03*
X99199Y1761899D03*
X99999Y1753575D03*
X101399Y1784700D03*
X85599Y1797350D03*
X96600Y1826000D03*
X86649Y1817100D03*
X90000Y1827900D03*
X93500D03*
X97999Y1843050D03*
X112999Y124050D03*
X111790Y132259D03*
X115876Y125973D03*
Y130050D03*
X114900Y177900D03*
X122397Y252688D03*
X122799Y249150D03*
X124999Y246050D03*
X123378Y255944D03*
X107499Y497050D03*
X107526Y528996D03*
X109400Y543200D03*
X106000D03*
X105100Y600000D03*
X107000Y604800D03*
X125499Y635550D03*
Y638950D03*
X124999Y643050D03*
X110500Y790200D03*
X111100Y813400D03*
X111200Y799450D03*
X111207Y810001D03*
X110700Y795700D03*
X111089Y806603D03*
X110800Y803100D03*
X110499Y834550D03*
X106749Y934367D03*
X108441Y924705D03*
X108845Y931657D03*
X109099Y928250D03*
X108200Y963600D03*
X107300Y986000D03*
X107400Y992900D03*
X124100Y1047100D03*
X123999Y1054050D03*
Y1050650D03*
X120100Y1053200D03*
X116700Y1063500D03*
X112699Y1058974D03*
X105499Y1080550D03*
X106718Y1076050D03*
X105999Y1085800D03*
X121500Y1083600D03*
X121100Y1075300D03*
X117499Y1079300D03*
X105600Y1069500D03*
X124423Y1077523D03*
Y1081177D03*
X120749Y1093990D03*
X125900Y1091282D03*
X116249Y1102550D03*
X112999Y1103740D03*
X123999Y1102550D03*
X108999Y1102050D03*
X106999Y1194550D03*
X106162Y1205702D03*
X114999Y1210363D03*
X118999Y1219050D03*
X123970Y1221573D03*
X119399Y1298113D03*
X116999Y1288050D03*
X120507Y1317050D03*
X111499Y1311800D03*
X107999Y1307713D03*
X116499Y1328013D03*
X120507Y1328096D03*
X113000Y1341000D03*
X107228Y1330552D03*
X107500Y1340500D03*
X109228Y1337090D03*
Y1333315D03*
X119499Y1339050D03*
X113500Y1352000D03*
X110499Y1365050D03*
X109999Y1355050D03*
X112440Y1358196D03*
X112999Y1361550D03*
X121000Y1364000D03*
X113500Y1344500D03*
Y1348154D03*
X125100Y1366000D03*
X117390Y1426201D03*
X119507Y1423540D03*
X117390Y1429976D03*
X104935Y1440634D03*
X104999Y1444941D03*
X107328Y1438218D03*
X114499Y1432050D03*
X107999Y1448050D03*
X124290Y1469241D03*
X123808Y1465050D03*
X106999Y1454450D03*
X105099Y1459150D03*
X123999Y1473050D03*
X122199Y1476050D03*
X118499Y1694050D03*
X117499Y1706050D03*
X109499Y1712213D03*
X104999Y1708963D03*
X117249Y1712090D03*
X112753Y1716613D03*
X122642Y1704243D03*
X112562Y1720613D03*
X123749Y1711550D03*
X109499Y1743550D03*
X107499Y1736550D03*
X109399Y1739550D03*
X106999Y1746290D03*
X110099Y1759875D03*
X123393Y1870859D03*
X123592Y1874254D03*
X127999Y157050D03*
X147099Y245350D03*
X141499Y427550D03*
Y423050D03*
X135499Y517550D03*
X138999Y524213D03*
X137899Y545451D03*
X138416Y553500D03*
X140940Y561800D03*
X141300Y565900D03*
X127999Y645550D03*
X131400Y644600D03*
X144238Y645356D03*
X128725Y636626D03*
X128479Y640589D03*
X141773Y643013D03*
X144238Y649131D03*
X140499Y649350D03*
X134300Y646400D03*
X141500Y711000D03*
X137100Y1084800D03*
X140800Y1076300D03*
X137481Y1077557D03*
X137477Y1081177D03*
X132499Y1094550D03*
X138600Y1124600D03*
X130699Y1210653D03*
X135850Y1322250D03*
X125999Y1315550D03*
X132999Y1319550D03*
X142667Y1319218D03*
X143700Y1332500D03*
X133475Y1331200D03*
X140000Y1332600D03*
X138000Y1359025D03*
X129000Y1356500D03*
X142999Y1456373D03*
X139815Y1454438D03*
X139235Y1460973D03*
X127898Y1462441D03*
X142900Y1460000D03*
X133090Y1699959D03*
X128749Y1703300D03*
X131999Y1710050D03*
X141500Y1715500D03*
X135499Y1710150D03*
X141999Y1764550D03*
X137999Y1861497D03*
Y1865151D03*
X141101Y1866545D03*
X140999Y1859550D03*
X135999Y1881550D03*
X152499Y149550D03*
X154200Y168500D03*
X149400Y166400D03*
X149999Y243504D03*
Y239729D03*
X157440Y283924D03*
Y303924D03*
Y313924D03*
X165699Y428050D03*
X153459Y427494D03*
X154101Y445550D03*
X159600Y446399D03*
X163549Y517100D03*
X152000Y520813D03*
X163449Y521650D03*
X149000Y537500D03*
X150500Y545000D03*
X160932Y549468D03*
X150750Y540416D03*
X156500Y554000D03*
X157000Y573851D03*
X160824Y577000D03*
X161000Y639100D03*
X158885Y679436D03*
Y689436D03*
X158385Y719436D03*
X159500Y814700D03*
X165499Y815550D03*
X153500Y834600D03*
X154799Y838050D03*
X153499Y918550D03*
X163500Y937100D03*
X160399Y922850D03*
X152500Y960000D03*
X154749Y979149D03*
Y968249D03*
X164700Y1085400D03*
X159000Y1083000D03*
X157700Y1114948D03*
X157600Y1124948D03*
X149562Y1315987D03*
X147400Y1321600D03*
X148024Y1333525D03*
X150338Y1453958D03*
X152499Y1462940D03*
X157440Y1490460D03*
Y1500460D03*
Y1520460D03*
Y1530460D03*
X157400Y1596550D03*
X160200Y1598500D03*
X165575Y1676975D03*
X152633Y1677967D03*
X150999Y1713550D03*
X165900Y1790500D03*
X161900Y1793400D03*
X159421Y1925972D03*
X175999Y82428D03*
X174999Y79050D03*
X175499Y86572D03*
X176399Y94872D03*
X178999Y79050D03*
X186999Y99050D03*
X169999Y129050D03*
X188999Y120800D03*
X173499Y149050D03*
X173500Y166315D03*
X187699Y492850D03*
X173100Y483100D03*
X172499Y491053D03*
X176799Y493850D03*
X188000Y484500D03*
X171722Y513827D03*
X182499Y532550D03*
X168453Y527949D03*
X183499Y556100D03*
X172660Y815731D03*
X169106Y815865D03*
X174199Y841050D03*
X172500Y919294D03*
X172000Y931600D03*
X171100Y935000D03*
X171000Y939500D03*
X172000Y961000D03*
X170250Y948500D03*
X179499Y1275550D03*
X181000Y1365500D03*
X180500Y1369900D03*
X179999Y1655887D03*
X171999Y1662250D03*
X169600Y1682300D03*
X169100Y1685800D03*
X174250Y1694500D03*
X181100Y1682700D03*
X177900Y1690400D03*
X205938Y72528D03*
X201499Y104550D03*
X205499Y105550D03*
X207999Y109550D03*
X197899Y165075D03*
X199900Y554050D03*
X193549Y575875D03*
X200000Y818000D03*
X200539Y890300D03*
X200799Y896600D03*
X198924Y975975D03*
X199149Y1362900D03*
X194700Y1385700D03*
X193500Y1647000D03*
X201499Y1781050D03*
X194049Y1792600D03*
X210605Y70692D03*
X210685Y74725D03*
X215138Y72559D03*
X210634Y66863D03*
X210638Y62959D03*
X225499Y68550D03*
X210738Y82159D03*
Y78459D03*
X230749Y76300D03*
X213499Y104650D03*
X223499Y108150D03*
X218499Y190550D03*
X225298Y281114D03*
X213499Y283864D03*
X214063Y318114D03*
X213400Y355300D03*
X224998Y357049D03*
X220000Y516400D03*
X216999Y686550D03*
X213999Y725050D03*
X230849Y726050D03*
X228999Y765550D03*
X218224Y765325D03*
X211750Y894600D03*
X229562Y904113D03*
X215499Y905550D03*
X221800Y1069300D03*
X221300Y1083238D03*
X229800Y1073600D03*
X226800Y1093400D03*
X224750Y1483950D03*
X229025Y1471576D03*
X227814Y1887513D03*
X223436Y1890465D03*
X229800Y1875700D03*
X218100Y1886400D03*
X214999Y1909550D03*
X213562Y1926113D03*
X220062Y1931113D03*
X213138Y1952703D03*
X210999Y1942050D03*
X246999Y51550D03*
X246499Y42550D03*
X246999Y69550D03*
Y60550D03*
X246499Y86050D03*
Y80550D03*
X245499Y100550D03*
X233749Y110800D03*
X237899Y107050D03*
X247800Y269700D03*
X250300Y275100D03*
X250400Y283100D03*
X239600Y278600D03*
X231800Y318414D03*
X233998Y357549D03*
X239400Y357400D03*
X246800Y677100D03*
X249700Y682500D03*
X238500Y680800D03*
X249800Y689900D03*
X252499Y726050D03*
X241600Y765700D03*
X236800Y765800D03*
X233500Y1066100D03*
X242000Y1066000D03*
X247500Y1085500D03*
X251500Y1136700D03*
X241000Y1469600D03*
X233700Y1481600D03*
X232650Y1493450D03*
X231800Y1887100D03*
X232314Y1890513D03*
X236225Y1883125D03*
X231999Y1914050D03*
X249600Y1896800D03*
X249499Y1928050D03*
X240964Y1934113D03*
X253999Y44050D03*
X253871Y291410D03*
X252935Y319114D03*
X254499Y697700D03*
X255000Y1125700D03*
X256000Y1133000D03*
X269500Y1135500D03*
X261999Y1516050D03*
X257499Y1911050D03*
X264499Y1964050D03*
X291999Y94050D03*
X282800Y87500D03*
X293999Y293550D03*
X284999Y338650D03*
X281499Y338550D03*
X294500Y339000D03*
X279939Y728610D03*
X285499Y745050D03*
X282099D03*
X292999Y743650D03*
X277039Y740300D03*
X282500Y1135000D03*
X295000Y1513000D03*
X289999Y1554650D03*
X293700Y1553351D03*
X276039Y1551300D03*
X283499Y1556050D03*
X279999D03*
X291400Y1561500D03*
X285499Y1930050D03*
X288709Y1948042D03*
X284999Y1947691D03*
X280689Y1942710D03*
X296099Y17100D03*
X305099Y17000D03*
X311400Y17100D03*
X308999Y87050D03*
X297499Y97550D03*
X315800Y100500D03*
X298800Y333000D03*
X301249Y346050D03*
X313039Y352350D03*
X308999Y716450D03*
X315999Y718950D03*
X298000Y743500D03*
X310999Y757050D03*
X314999Y1527550D03*
X297800Y1561600D03*
X312999Y1566050D03*
X310249Y1569800D03*
X313499Y1919050D03*
X310499Y1957050D03*
X315999Y1958550D03*
X317000Y17300D03*
X324800Y89400D03*
X323400Y105200D03*
X326499Y334054D03*
Y337454D03*
X321900Y364600D03*
X327999Y740550D03*
X323249Y749010D03*
X327749Y744050D03*
X324959Y766750D03*
X329499Y801550D03*
X330540Y795509D03*
X320499Y798050D03*
X326500Y1550200D03*
X324000Y1562500D03*
X330300Y1561200D03*
X323999Y1577250D03*
X325221Y1927272D03*
X331622Y1944767D03*
X329999Y1952273D03*
X332103Y1948133D03*
X327100Y1966472D03*
X343499Y31650D03*
X354999Y72050D03*
X343499Y60150D03*
X341499Y63050D03*
Y67110D03*
X357503Y77043D03*
X344520Y406329D03*
X350499Y597300D03*
Y715050D03*
X340699Y1046086D03*
X345499Y1096550D03*
X345424Y1310050D03*
X347324Y1524000D03*
X354500Y1559500D03*
X349774Y1582900D03*
X354000Y1584900D03*
X353499Y1710450D03*
X348499Y1762050D03*
X342999Y1947409D03*
X342621Y1943409D03*
X358999Y61550D03*
X374499Y77550D03*
X365499Y86550D03*
X371999Y549300D03*
X375999Y698550D03*
X371500Y880600D03*
X364499Y1099050D03*
X372999Y1123550D03*
X370149Y1320050D03*
X366149Y1554050D03*
X377900Y1703800D03*
X398799Y36152D03*
X381999Y50150D03*
X382339Y41610D03*
X381999Y53550D03*
X394199Y45050D03*
X381999Y57050D03*
X385999Y78050D03*
X400499Y406329D03*
X394649Y630600D03*
X390999Y1514398D03*
Y1517798D03*
X385499Y1735050D03*
X401499Y80550D03*
X402499Y1476850D03*
X400999Y1575550D03*
X645549Y1815134D03*
X644360Y1819137D03*
X659549Y1810634D03*
X690249Y1805634D03*
X707600Y1815600D03*
X711652Y1822109D03*
X711848Y1825504D03*
X732549Y1806634D03*
X733149Y1798634D03*
X733049Y1814134D03*
X752999Y746842D03*
X757499Y745342D03*
Y1079550D03*
X755600Y1149800D03*
X758499Y1371050D03*
X757999Y1484050D03*
X758199Y1553650D03*
X755000Y1825000D03*
X758499Y1893550D03*
X759114Y1957673D03*
X770999Y302050D03*
Y290050D03*
Y295550D03*
X763571Y295622D03*
X777999Y296050D03*
X772499Y323050D03*
X772873Y326924D03*
X760778Y345050D03*
X768178Y333964D03*
X780499Y330050D03*
X771105Y722789D03*
X766499Y732842D03*
X762999Y734550D03*
X769999Y733050D03*
X771999Y1124550D03*
X772499Y1130050D03*
X779499Y1131050D03*
X767083Y1134550D03*
X768199Y1138590D03*
X774542Y1530050D03*
X774577Y1533796D03*
X771225Y1539474D03*
X767936Y1540336D03*
X774500Y1788000D03*
X770999Y1820550D03*
X771499Y1936550D03*
X767999Y1945173D03*
X764908Y1946592D03*
X771499Y1940050D03*
X785499Y291050D03*
X786978Y298529D03*
X791499Y333050D03*
X789999Y336550D03*
X784499Y334050D03*
X781999Y725550D03*
X788999Y736050D03*
X791999Y733050D03*
X784939Y733550D03*
X792154Y1135926D03*
X784439Y1136550D03*
X789499Y1138050D03*
X784499Y1529050D03*
X784577Y1535628D03*
X791499Y1543550D03*
X793999Y1541050D03*
X788000Y1788000D03*
X793000Y1803500D03*
X795849Y1805500D03*
X791999Y1819050D03*
X783499Y1827050D03*
X802499Y1951550D03*
X800431Y1941193D03*
X785939Y1946800D03*
X792499Y1949050D03*
X794499Y1941050D03*
X782999Y1937050D03*
X802099Y1961950D03*
X820749Y163850D03*
X813249Y163800D03*
X821999Y193116D03*
X809940Y264940D03*
X822100Y261700D03*
Y279500D03*
X816700Y274300D03*
X820600Y664300D03*
X808660Y667540D03*
X813200Y675900D03*
X807000Y1072900D03*
X815400Y1078800D03*
X803199Y1151850D03*
X822100Y1466800D03*
X809960Y1478040D03*
X814700Y1486300D03*
X804899Y1556950D03*
X812000Y1799500D03*
X821249Y1791250D03*
X811000Y1793000D03*
X822499Y1815164D03*
X807000Y1822300D03*
X803500Y1822708D03*
X822700Y1871100D03*
X810900Y1882440D03*
X805900Y1887560D03*
X841499Y135550D03*
X827499Y163550D03*
X839249Y164050D03*
X829917Y216200D03*
X833576Y215432D03*
X837999Y219550D03*
X842499Y280924D03*
X827500Y274500D03*
X836500Y274950D03*
X827499Y313424D03*
X829800Y666650D03*
X835150Y677650D03*
X825700Y1083100D03*
X825800Y1072300D03*
X827700Y1487600D03*
X836625Y1487400D03*
X828500Y1877800D03*
X834799Y1946950D03*
X861999Y146550D03*
X854400Y264600D03*
X847878Y250040D03*
X851278Y249974D03*
X847450Y246666D03*
X850999Y246550D03*
X858478Y274050D03*
X865499Y288050D03*
X851172Y655432D03*
X847772Y655370D03*
X851197Y652032D03*
X847493Y651981D03*
X852696Y671197D03*
X850833Y1061441D03*
X847233Y1061492D03*
X847355Y1058094D03*
X851042Y1058047D03*
X852333Y1077716D03*
X860133Y1084142D03*
X864499Y1128750D03*
X860799Y1358925D03*
X861849Y1376050D03*
X848888Y1466402D03*
X852288Y1466346D03*
X848861Y1462463D03*
X852429Y1462948D03*
X854327Y1477550D03*
X858827Y1485696D03*
X863699Y1501250D03*
X862800Y1712700D03*
X851500Y1821400D03*
X849375Y1824982D03*
X854905Y1825583D03*
X853499Y1871036D03*
X850099Y1871056D03*
X854480Y1867578D03*
X849999Y1867550D03*
X863788Y1866953D03*
X865501Y1858747D03*
X859314Y1891365D03*
X854814Y1883550D03*
X863699Y1906450D03*
X857099Y1917650D03*
X882499Y147050D03*
X867500Y163924D03*
X867576Y159924D03*
X878078Y240103D03*
Y243878D03*
X874928Y238822D03*
X874790Y244748D03*
X871999Y283924D03*
X872136Y273924D03*
X886600Y303924D03*
X868799Y294750D03*
X867899Y321550D03*
X886200Y313924D03*
X868299Y336150D03*
X879750Y570550D03*
X879950Y565050D03*
X878596Y645573D03*
X874999Y644550D03*
X878596Y649348D03*
X875270Y650059D03*
X883083Y979183D03*
X879708Y971892D03*
X878233Y1051095D03*
X877964Y1054485D03*
X874733Y1055792D03*
X874999Y1049550D03*
X872086Y1084948D03*
X871999Y1094948D03*
X871499Y1124948D03*
X872086Y1114948D03*
X866700Y1379796D03*
X866596Y1375796D03*
X878054Y1456450D03*
X877853Y1459991D03*
X874499Y1460550D03*
X874986Y1454983D03*
X872086Y1490460D03*
X871999Y1500460D03*
Y1520460D03*
X872086Y1530460D03*
X867523Y1542821D03*
X867199Y1535150D03*
X886439Y1717600D03*
X873800Y1733600D03*
X879700Y1786300D03*
X879664Y1782213D03*
X866914Y1861840D03*
Y1865615D03*
X871921Y1905972D03*
X871421Y1895972D03*
X872086Y1925972D03*
Y1935972D03*
X901499Y92050D03*
X897555Y90494D03*
X898999Y99050D03*
X902499Y110550D03*
X898999D03*
X907499Y131800D03*
X896999Y141550D03*
X902999Y556050D03*
X900499Y962100D03*
X900999Y979050D03*
X889800Y1711500D03*
X923761Y85550D03*
X928561Y95181D03*
X928428Y83714D03*
X928508Y87747D03*
X928561Y91481D03*
X928457Y79885D03*
X928461Y75981D03*
X916499Y115050D03*
X926999D03*
Y122050D03*
X910999Y124550D03*
X916499Y172550D03*
X922049Y574375D03*
Y978575D03*
X921549Y1788475D03*
X917499Y1796550D03*
X932961Y85581D03*
X943499Y82550D03*
X930999Y115550D03*
X938499D03*
X946899Y122550D03*
X937999Y122050D03*
X934499Y118750D03*
X939549Y175175D03*
X961499Y93350D03*
X958999Y96050D03*
X961499Y100050D03*
X966499Y552050D03*
X965999Y954550D03*
X965150Y1639500D03*
X961702Y1636102D03*
X969600Y1638300D03*
X967600Y1651100D03*
X971558Y1646500D03*
X981200Y1618002D03*
X986400Y1639302D03*
X987100Y1624900D03*
X981200Y1625800D03*
X990425Y1633898D03*
X987029Y1634075D03*
X977500Y1660500D03*
X989502Y1646000D03*
X988800Y1658300D03*
X981500Y1653000D03*
X980800Y1659600D03*
X982050Y1649302D03*
X978000Y1668000D03*
X989000Y1663802D03*
X987200Y1675600D03*
X989900Y1678800D03*
X974000Y1670700D03*
X984211Y1667500D03*
G54D14*
X68898Y17047D03*
Y190275D03*
Y422559D03*
Y595787D03*
Y828071D03*
Y1001299D03*
Y1233583D03*
Y1406811D03*
Y1639095D03*
Y1812323D03*
X167323Y179803D03*
Y353031D03*
Y585315D03*
Y758543D03*
Y990827D03*
Y1164055D03*
Y1396339D03*
Y1569567D03*
Y1801851D03*
Y1975079D03*
X895669Y179803D03*
Y353031D03*
Y585315D03*
Y758543D03*
Y990827D03*
Y1164055D03*
Y1396339D03*
Y1569567D03*
Y1801851D03*
Y1975079D03*
G54D15*
X129921Y17716D03*
X994093Y1889751D03*
G54D16*
G01X-87137Y-139897D02*
Y-107897D01*
G01X-75137Y-123897D02*
G02I-12000J0D01*
G01X-80287D02*
G02I-6850J0D01*
G01X-71137D02*
X-103137D01*
G01X-71137Y-139897D02*
Y-219897D01*
G01D02*
X1129963D01*
G01X-71137Y-175397D02*
X1129963D01*
G01X-71137Y-139897D02*
X1129963D01*
G01X315800Y100500D02*
X261511Y154789D01*
X147361D01*
X97600Y204550D01*
X95350D01*
G01X89800Y208550D02*
X98126D01*
X148687Y157989D01*
X262837D01*
X319001Y101825D01*
Y99704D01*
X321300Y97405D01*
Y92400D01*
X324300Y89400D01*
X324800D01*
G01X177900Y1690400D02*
X174673D01*
X158700Y1706373D01*
Y1772103D01*
X99003Y1831800D01*
X92874D01*
X90000Y1828926D01*
Y1827900D01*
G01X169600Y1682300D02*
X169900Y1682600D01*
X170427D01*
X172300Y1684473D01*
Y1688247D01*
X155500Y1705047D01*
Y1770777D01*
X97677Y1828600D01*
X94200D01*
X93500Y1827900D01*
G01X147400Y1321600D02*
X150624Y1324824D01*
Y1330892D01*
X151725Y1331993D01*
Y1335057D01*
X150624Y1336158D01*
Y1362376D01*
X145800Y1367200D01*
X126300D01*
X125100Y1366000D01*
G01X129000Y1356500D02*
X131899Y1353601D01*
Y1340701D01*
X140000Y1332600D01*
G01X169100Y1685800D02*
X147249D01*
X133090Y1699959D01*
G01X154200Y168500D02*
X169829D01*
X171529Y170200D01*
X176965D01*
X242050Y235285D01*
Y274250D01*
X250400Y282600D01*
Y283100D01*
G01X239600Y278600D02*
Y276326D01*
X238850Y275576D01*
Y236611D01*
X175639Y173400D01*
X170203D01*
X168603Y171800D01*
X152500D01*
X149400Y168700D01*
Y166400D01*
G01X249800Y689900D02*
Y688200D01*
X241700Y680100D01*
Y636339D01*
X212599Y607238D01*
Y606522D01*
X209027Y602950D01*
X208311D01*
X181035Y575674D01*
Y575673D01*
X179162Y573800D01*
X159497D01*
X159446Y573851D01*
X157000D01*
G01X160824Y577000D02*
X177835D01*
X206985Y606150D01*
X207701D01*
X209399Y607848D01*
Y608564D01*
X238500Y637665D01*
Y680800D01*
G01X154749Y979149D02*
X164723D01*
X229800Y1044226D01*
Y1073600D01*
G01X154749Y968249D02*
X158349D01*
X233000Y1042900D01*
Y1057000D01*
X242000Y1066000D01*
G01X165900Y1790500D02*
X166100Y1790300D01*
X184265D01*
X220550Y1826585D01*
Y1868400D01*
X227850Y1875700D01*
X229800D01*
G01X161900Y1793400D02*
X162200Y1793700D01*
X182751D01*
X217350Y1828299D01*
Y1885650D01*
X218100Y1886400D01*
G01X181000Y1365500D02*
X184600Y1369100D01*
Y1413200D01*
X241000Y1469600D01*
G01X180500Y1369900D02*
X181400Y1370800D01*
Y1414526D01*
X233700Y1466826D01*
Y1481600D01*
G01X181100Y1682700D02*
Y1705449D01*
X172499Y1714050D01*
G01X250300Y275100D02*
Y277916D01*
X267498Y295114D01*
G01X249700Y682500D02*
Y682751D01*
X268499Y701550D01*
G01X342463Y-139897D02*
Y-219897D01*
G01X479963Y-139897D02*
Y-219897D01*
G01X594963Y-139897D02*
Y-219897D01*
G01X762463Y-139897D02*
Y-219897D01*
G01X867576Y159924D02*
X866974D01*
X855500Y171398D01*
Y210574D01*
X818900Y247174D01*
Y272100D01*
X816700Y274300D01*
G01X822100Y261700D02*
Y248500D01*
X858700Y211900D01*
Y172724D01*
X867500Y163924D01*
G01X813200Y675900D02*
X817400Y671700D01*
Y626539D01*
X876589Y567350D01*
X877650D01*
X879950Y565050D01*
G01X879750Y570550D02*
X877915D01*
X820600Y627865D01*
Y664300D01*
G01X879708Y971892D02*
X875617Y975983D01*
X874556D01*
X822600Y1027939D01*
Y1071900D01*
X815700Y1078800D01*
X815400D01*
G01X822100Y1466800D02*
Y1424400D01*
X866700Y1379800D01*
Y1379796D01*
G01X814700Y1486300D02*
X818899Y1482101D01*
Y1423071D01*
X866174Y1375796D01*
X866596D01*
G01X822700Y1871100D02*
Y1843300D01*
X879700Y1786300D01*
G01X805900Y1887560D02*
X806740Y1886720D01*
X811500D01*
X815500Y1882720D01*
Y1845974D01*
X879261Y1782213D01*
X879664D01*
G01X883083Y979183D02*
X875882D01*
X825800Y1029265D01*
Y1072300D01*
G01X932463Y-139897D02*
Y-219897D01*
G01X1129963Y-139897D02*
Y-219897D01*
G01X1157963Y-123897D02*
G02I-12000J0D01*
G01X1152813D02*
G02I-6850J0D01*
G01X1161963D02*
X1129963D01*
G01X1145963Y-139897D02*
Y-107897D01*
G54D17*
G01X123500Y1360300D02*
X126800D01*
X130000Y1363500D01*
X138500D01*
X141500Y1360500D01*
Y1340049D01*
X148024Y1333525D01*
G01X151300Y1049300D02*
X180400D01*
X224500Y1093400D01*
X226800D01*
G54D18*
G01X17720Y1893930D02*
Y1903132D01*
G01D02*
Y1912334D01*
G01X8518Y1903132D02*
X17720D01*
G01D02*
X26922D01*
G01X29531Y300347D02*
Y309549D01*
G01D02*
Y318751D01*
G01X20329Y309549D02*
X29531D01*
G01D02*
X38733D01*
G01X29531Y1020308D02*
Y1029510D01*
G01D02*
Y1038712D01*
G01X68898Y12645D02*
Y17047D01*
G01D02*
Y21449D01*
G01X62346Y17047D02*
X68898D01*
G01D02*
X75450D01*
G01X68898Y185873D02*
Y190275D01*
G01D02*
Y194677D01*
G01X62346Y190275D02*
X68898D01*
G01D02*
X75450D01*
G01X68898Y418157D02*
Y422559D01*
G01D02*
Y426961D01*
G01X62346Y422559D02*
X68898D01*
G01D02*
X75450D01*
G01X68898Y591385D02*
Y595787D01*
G01D02*
Y600189D01*
G01X62346Y595787D02*
X68898D01*
G01D02*
X75450D01*
G01X68898Y823669D02*
Y828071D01*
G01D02*
X75450D01*
G01X68898Y996897D02*
Y1001299D01*
G01D02*
Y1005701D01*
G01Y1229181D02*
Y1233583D01*
G01X65622Y1229181D02*
X68898Y1233583D01*
G01Y1402409D02*
Y1406811D01*
G01D02*
Y1411213D01*
G01Y1812323D02*
X75450Y1807921D01*
G01X68898Y1812323D02*
X75450D01*
G01X119869Y17716D02*
X129921D01*
G01Y7664D02*
Y17716D01*
G01X167323Y175401D02*
Y179803D01*
G01D02*
Y184205D01*
G01X160771Y179803D02*
X167323D01*
G01D02*
X173875D01*
G01X167323Y348629D02*
Y353031D01*
G01D02*
Y357433D01*
G01X160771Y353031D02*
X167323D01*
G01D02*
X173875D01*
G01X167323Y580913D02*
Y585315D01*
G01D02*
Y589717D01*
G01X160771Y585315D02*
X167323D01*
G01D02*
X173875D01*
G01X167323Y754141D02*
Y758543D01*
G01D02*
Y762945D01*
G01Y758543D02*
X173875D01*
G01X167323Y990827D02*
Y995229D01*
G01X160771Y990827D02*
X167323D01*
G01Y1159653D02*
Y1164055D01*
G01D02*
Y1168457D01*
G01X160771Y1164055D02*
X167323D01*
G01D02*
X173875D01*
G01X167323Y1391937D02*
Y1396339D01*
G01D02*
Y1400741D01*
G01X160771Y1396339D02*
X167323D01*
G01D02*
X173875D01*
G01X167323Y1565165D02*
Y1569567D01*
G01D02*
Y1573969D01*
G01X160771Y1569567D02*
X167323D01*
G01D02*
X173875D01*
G01X167323Y1797449D02*
Y1801851D01*
G01D02*
Y1806253D01*
G01X160771Y1801851D02*
X167323D01*
G01D02*
X173875D01*
G01X167323Y1970677D02*
Y1975079D01*
G01D02*
Y1979481D01*
G01X160771Y1975079D02*
X167323D01*
G01D02*
X173875D01*
G01X271657Y258497D02*
Y267699D01*
G01D02*
Y276901D01*
G01X262455Y267699D02*
X271657D01*
G01D02*
X280859D01*
G01X271657Y664008D02*
Y673210D01*
G01D02*
Y682412D01*
G01X262455Y673210D02*
X271657D01*
G01D02*
X280859D01*
G01X271657Y1069520D02*
Y1078722D01*
G01X262455D02*
X271657D01*
G01D02*
X280859D01*
G01X271657Y1475032D02*
Y1484234D01*
G01D02*
Y1493436D01*
G01X262455Y1484234D02*
X271657D01*
G01D02*
X280859D01*
G01X271657Y1880544D02*
Y1889746D01*
G01D02*
Y1898948D01*
G01X262455Y1889746D02*
X271657D01*
G01D02*
X280859D01*
G01X895669Y175401D02*
Y179803D01*
G01D02*
Y184205D01*
G01X889117Y179803D02*
X895669D01*
G01D02*
X902221D01*
G01X895669Y348629D02*
Y353031D01*
G01D02*
Y357433D01*
G01X889117Y353031D02*
X895669D01*
G01D02*
X902221D01*
G01X895669Y580913D02*
Y585315D01*
G01D02*
Y589717D01*
G01X889117Y585315D02*
X895669D01*
G01D02*
X902221D01*
G01X895669Y754141D02*
Y758543D01*
G01D02*
Y762945D01*
G01X889117Y758543D02*
X895669D01*
G01D02*
X902221D01*
G01X895669Y986425D02*
Y990827D01*
G01D02*
Y995229D01*
G01X889117Y990827D02*
X895669D01*
G01D02*
X902221D01*
G01X895669Y1159653D02*
Y1164055D01*
G01D02*
Y1168457D01*
G01X889117Y1164055D02*
X895669D01*
G01D02*
X902221D01*
G01X895669Y1391937D02*
Y1396339D01*
G01D02*
Y1400741D01*
G01X889117Y1396339D02*
X895669D01*
G01D02*
X902221D01*
G01X895669Y1565165D02*
Y1569567D01*
G01D02*
Y1573969D01*
G01X889117Y1569567D02*
X895669D01*
G01D02*
X902221D01*
G01X895669Y1797449D02*
Y1801851D01*
G01D02*
Y1806253D01*
G01X889117Y1801851D02*
X895669D01*
G01D02*
X902221D01*
G01X895669Y1970677D02*
Y1975079D01*
G01D02*
Y1979481D01*
G01X889117Y1975079D02*
X895669D01*
G01D02*
X902221D01*
G01X984896Y149588D02*
X994098D01*
G01X984896Y673210D02*
X994098D01*
G01X984896Y1068880D02*
X994098D01*
G01X984041Y1889751D02*
X994093D01*
G01X994098Y140386D02*
Y149588D01*
G01D02*
Y158790D01*
G01Y149588D02*
X1003300D01*
G01X994098Y664008D02*
Y673210D01*
G01D02*
Y682412D01*
G01Y673210D02*
X1003300D01*
G01X994098Y1059678D02*
Y1068880D01*
G01D02*
Y1078082D01*
G01Y1068880D02*
X1003300D01*
G01X994093Y1879699D02*
Y1889751D01*
G01D02*
Y1899803D01*
G01Y1889751D02*
X1004145D01*
G54D19*
G01X127999Y645550D02*
G03X129000Y647967I-2417J2417D01*
G01Y648799D01*
G03X128361Y650341I-2180J0D01*
G01X126951Y651751D01*
G02X125900Y654290I2539J2538D01*
G01Y657699D01*
G02X127099Y660597I4097J2D01*
G01X127551Y661049D01*
X127552Y661048D01*
G02X129850Y662000I2298J-2297D01*
G01X136626D01*
G02X139648Y660748I0J-4273D01*
G01X139649Y660749D01*
X147799Y652599D01*
X147798Y652598D01*
G02X149471Y648562I-4037J-4038D01*
G01Y642378D01*
G03X151199Y640650I1728J0D01*
G01X154386D01*
G02X157648Y639299I0J-4614D01*
G02X158999Y636037I-3263J-3262D01*
G01Y612171D01*
G02X157499Y608550I-5121J0D01*
G01X148787Y599837D01*
G03X147839Y597550I2287J-2288D01*
G01Y546149D01*
G02X146318Y542478I-5193J1D01*
G01X69944Y466104D01*
G02X64582Y463883I-5362J5362D01*
G01X30153D01*
G03X29733Y463708I2J-596D01*
G02X27841Y462948I-1835J1833D01*
G01X27265Y462961D01*
G03X26486Y462648I-23J-1068D01*
G01X131400Y644600D02*
G02X130200Y647497I2897J2897D01*
G01Y648800D01*
G03X129210Y651190I-3380J0D01*
G01X127800Y652600D01*
G02X127100Y654290I1690J1690D01*
G01Y657700D01*
G02X127948Y659748I2897J0D01*
G01X128400Y660200D01*
G02X129849Y660800I1449J-1449D01*
G01X136627D01*
G02X138800Y659900I0J-3073D01*
G01X146950Y651750D01*
G02X148271Y648561I-3189J-3189D01*
G01Y642378D01*
G03X151199Y639450I2928J0D01*
G01X154385D01*
G02X156799Y638450I0J-3414D01*
G02X157799Y636036I-2414J-2414D01*
G01Y612172D01*
G02X156651Y609398I-3921J-2D01*
G01X156650Y609399D01*
X147938Y600686D01*
G03X146640Y597550I3136J-3135D01*
G01X146639D01*
Y594555D01*
G02X146370Y594286I-269J0D01*
G01X146369D01*
G03X146100Y594017I0J-269D01*
G01Y592155D01*
G03X146369Y591886I269J0D01*
G01X146370D01*
G02X146639Y591617I0J-269D01*
G01Y589755D01*
G02X146370Y589486I-269J0D01*
G01X146369D01*
G03X146100Y589217I0J-269D01*
G01Y587355D01*
G03X146369Y587086I269J0D01*
G01X146370D01*
G02X146639Y586817I0J-269D01*
G01Y584955D01*
G02X146370Y584686I-269J0D01*
G01X146369D01*
G03X146100Y584417I0J-269D01*
G01Y582555D01*
G03X146369Y582286I269J0D01*
G01X146370D01*
G02X146639Y582017I0J-269D01*
G01Y559629D01*
G02X146370Y559360I-269J0D01*
G01X146369D01*
G03X146100Y559091I0J-269D01*
G01Y557229D01*
G03X146369Y556960I269J0D01*
G01X146370D01*
G02X146639Y556691I0J-269D01*
G01Y554829D01*
G02X146370Y554560I-269J0D01*
G01X146369D01*
G03X146100Y554291I0J-269D01*
G01Y552429D01*
G03X146369Y552160I269J0D01*
G01X146370D01*
G02X146639Y551891I0J-269D01*
G01Y546150D01*
G02X145469Y543327I-3993J1D01*
G01X69095Y466953D01*
G02X64580Y465083I-4515J4515D01*
G01X30154D01*
G03X28884Y464557I0J-1796D01*
G02X26914I-985J985D01*
G02X26499Y465559I1002J1002D01*
G01Y466250D01*
G01X123999Y1054050D02*
G03X126001Y1053075I2414J2414D01*
G01X126002D01*
G03X126413Y1053050I412J3389D01*
G01X127000D01*
G02X129042Y1052204I-1J-2890D01*
G01Y1052203D01*
G02X129999Y1049893I-2309J-2310D01*
G01Y1047141D01*
G02X128947Y1044602I-3590J0D01*
G01X128948Y1044601D01*
X125273Y1040926D01*
G03X123300Y1036163I4763J-4763D01*
G01Y819233D01*
G02X119600Y810300I-12633J0D01*
G01X117582Y808282D01*
G03X117051Y807000I1282J-1282D01*
G01Y520376D01*
G02X115769Y517279I-4379J-1D01*
G01X113708Y515218D01*
X79369Y480880D01*
G02X76352Y479631I-3016J3017D01*
G01X31040D01*
G03X29777Y479107I1J-1786D01*
G02X29561Y478924I-1203J1201D01*
G02X27936Y478404I-1625J2278D01*
G01X26299D01*
G01X123999Y1050650D02*
X124811Y1051463D01*
G02X125745Y1051850I934J-934D01*
G01X126999D01*
Y1051849D01*
G02X128194Y1051355I1J-1690D01*
G02X128799Y1049894I-1461J-1461D01*
G01Y1047140D01*
G02X128099Y1045450I-2390J0D01*
G01X124424Y1041775D01*
G03X122100Y1036164I5612J-5611D01*
G01Y819232D01*
X122099Y819233D01*
G02X118752Y811148I-11433J-2D01*
G01X118751Y811149D01*
X116733Y809131D01*
G03X115851Y807000I2131J-2130D01*
G01Y520376D01*
G02X114920Y518128I-3179J0D01*
G01X114270Y517478D01*
X114269D01*
X78520Y481729D01*
G02X76352Y480831I-2168J2168D01*
G01X31039D01*
G03X28927Y479956I0J-2987D01*
G02X28573Y479809I-354J353D01*
G01X27807D01*
G02X27181Y480068I0J886D01*
G01X27062Y480187D01*
G02X26921Y480528I342J341D01*
G01Y480632D01*
G03X26884Y480817I-483J0D01*
G01X26720Y481213D01*
G03X26686Y481386I-452J1D01*
G01X26515Y481798D01*
G01X26599Y525648D02*
Y525867D01*
G02X28158Y527061I1237J0D01*
G03X29562Y526875I1404J5202D01*
G01X39059D01*
G02X39346Y526588I0J-287D01*
G01Y526587D01*
G03X39633Y526300I287J0D01*
G01X41459D01*
G03X41746Y526587I0J287D01*
G01Y526588D01*
G02X42033Y526875I287J0D01*
G01X43859D01*
G02X44146Y526588I0J-287D01*
G01Y526587D01*
G03X44433Y526300I287J0D01*
G01X46259D01*
G03X46546Y526587I0J287D01*
G01Y526588D01*
G02X46833Y526875I287J0D01*
G01X48659D01*
G02X48946Y526588I0J-287D01*
G01Y526587D01*
G03X49233Y526300I287J0D01*
G01X51059D01*
G03X51346Y526587I0J287D01*
G01Y526588D01*
G02X51633Y526875I287J0D01*
G01X54499D01*
G02X57359Y525691I1J-4044D01*
G01X58499Y524550D01*
G03X73470Y518350I14969J14970D01*
G01X86373D01*
G02X86673Y518050I0J-300D01*
G03X86973Y517750I300J0D01*
G01X88773D01*
G03X89073Y518050I0J300D01*
G02X89373Y518350I300J0D01*
G01X95117D01*
G02X96201Y517901I0J-1533D01*
G02X96800Y516455I-1446J-1446D01*
G01Y515900D01*
G02X95951Y513852I-2897J1D01*
G01X95500Y513400D01*
G01X26599Y529302D02*
G03X29561Y528075I2962J2962D01*
G01X54499D01*
Y528074D01*
G02X58208Y526540I3J-5244D01*
G01X59348Y525399D01*
G03X73469Y519550I14121J14121D01*
G01X95117D01*
G02X97049Y518750I0J-2733D01*
G01Y518749D01*
G02X98000Y516456I-2294J-2295D01*
G01Y515573D01*
G03X98900Y513400I3073J0D01*
M02*
